 
 
Open CloudServer  
chassis management 
specification 
V1.0 
 
Authors: 
Badriddine Khessib, Director of Platform Software Engineering, Microsoft 
Bryan Kelly, Senior Platform Software Engineer, Microsoft 
 


 
2 January 28, 2014 
1 Revision History 
 
Date Name Description 
1/28/2014  Version 1.0 
   
   
   
   
   
   
   
 
 
 
  



Open Compute Project  Open CloudServer chassis management specification 
http://opencompute.org 3 
© 2014 Microsoft Corporation. 
 
As of January 28, 2014, the following persons or entities have made this Specification available under 
the Open Web Foundation Final Specification Agreement (OWFa 1.0), which is available at 
http://www.openwebfoundation.org/legal/the-owf-1-0-agreements/owfa-1-0 Microsoft Corporation.  
You can review the signed copies of the Open Web Foundation Agreement Version 1.0 for this 
Specification at http://opencompute.org/licensing/, which may also include additional parties to those 
listed above. 
Your use of this Specification may be subject to other third party rights. THIS SPECIFICATION IS 
PROVIDED "AS IS." The contributors expressly disclaim any warranties (express, implied, or otherwise), 
including implied warranties of merchantability, noninfringement, fitness for a particular purpose, or title, 
related to the Specification. The entire risk as to implementing or otherwise using the Specification is 
assumed by the Specification implementer and user. IN NO EVENT WILL ANY PARTY BE LIABLE TO ANY 
OTHER PARTY FOR LOST PROFITS OR ANY FORM OF INDIRECT, SPECIAL, INCIDENTAL, OR 
CONSEQUENTIAL DAMAGES OF ANY CHARACTER FROM ANY CAUSES OF ACTION OF ANY KIND WITH 
RESPECT TO THIS SPECIFICATION OR ITS GOVERNING AGREEMENT, WHETHER BASED ON BREACH OF 
CONTRACT, TORT (INCLUDING NEGLIGENCE), OR OTHERWISE, AND WHETHER OR NOT THE OTHER 
PARTY HAS BEEN ADVISED OF THE POSSIBILITY OF SUCH DAMAGE. 
CONTRIBUTORS AND LICENSORS OF THIS SPECIFICATION MAY HAVE MENTIONED CERTAIN 
TECHNOLOGIES THAT ARE MERELY REFERENCED WITHIN THIS SPECIFICATION AND NOT LICENSED 
UNDER THE OWF CLA OR OWFa. THE FOLLOWING IS A LIST OF MERELY REFERENCED TECHNOLOGY: 
INTELLIGENT PLATFORM MANAGEMENT INTERFACE (IPMI), I2C TRADEMARK OF PHILLIPS 
SEMICONDUCTOR. IMPLEMENTATION OF THESE TECHNOLOGIES MAY BE SUBJECT TO THEIR OWN 
LEGAL TERMS.  



 
4 January 28, 2014 
2 Scope 
This document details the Open CloudServer chassis management. 
3 Contents 
1 Revision History ......................................................................................................................... 2 
2 Scope ......................................................................................................................................... 4 
3 Contents .................................................................................................................................... 4 
4 Overview.................................................................................................................................... 6 
5 Chassis Manager ........................................................................................................................ 6 
5.1 Features ........................................................................................................................ 7 
5.2 Signal Interface ........................................................................................................... 10 
5.3 Blade Management .................................................................................................... 15 
5.4 Power Control ............................................................................................................ 15 
5.5 Communication Ports ................................................................................................. 17 
5.6 Mechanical Specifications .......................................................................................... 18 
5.7 Chassis LEDs ................................................................................................................ 19 
6 Systems Management Operations .......................................................................................... 20 
6.1 Rack and Chassis Manager Commands ...................................................................... 21 
6.2 In-Band Management Commands ............................................................................. 22 
6.3 Out-of-Band Management Commands ...................................................................... 24 
7 Chassis Manager Services ........................................................................................................ 24 
7.1 Fan Control Protocol .................................................................................................. 26 
7.2 Blade State Management ........................................................................................... 30 
7.3 Chassis Manager Component Failure Scenarios ........................................................ 31 
8 Chassis Manager/Blade API ..................................................................................................... 32 
8.1 Blade Implementation Requirements ........................................................................ 35 
8.2 Request and Response Packet Formats ..................................................................... 36 
8.3 Packet Framing ........................................................................................................... 38 
8.4 Serial Console Redirection.......................................................................................... 40 
8.5 Chassis Manager Serial Port Session .......................................................................... 41 
8.6 Command-Completion Codes .................................................................................... 42 



Open Compute Project  Open CloudServer chassis management specification 
http://opencompute.org 5 
8.7 Blade Command Payload ........................................................................................... 44 
8.8 Command Formats ..................................................................................................... 48 
9 Chassis Manager REST API ....................................................................................................... 64 
9.1 User Roles and API Access .......................................................................................... 64 
9.2 Encryption and Service Credentials ............................................................................ 64 
9.3 Client Credentials/Authentication.............................................................................. 65 
9.4 Role-Based API-Level Authorization ........................................................................... 65 
9.5 REST API: Response and Completion Codes ............................................................... 69 
9.6 REST API: Descriptions, Usage Scenarios, and Sample Responses ............................. 70 
10 Command Line Interface ....................................................................................................... 135 
10.1 Install the Chassis Manager Service ......................................................................... 135 
10.2 State and Information Commands ........................................................................... 136 
10.3 Blade Management Commands ............................................................................... 144 
10.4 Chassis Manager Management Commands ............................................................. 155 
10.5 Blade and Serial Console Session Commands .......................................................... 163 
10.6 CLI Over Serial (WCSCLI+) ......................................................................................... 166 
 
 
  



 
6 January 28, 2014 
4 Overview 
This document describes systems management for the Open CloudServer system. 
System management uses the chassis manager (CM) to present a consistent, 
optimized interface for the complete rack infrastructure, including the in-band and 
out-of-band (OOB) management paths. 
The chassis manager provides the front end through an applications interface 
(RESTful web API) for automated management and through a command-line 
interface (CLI) for manual management. The chassis manager manages all devices 
within the rack and communicates directly with the blade management system 
through a serial multiplexor. 
5 Chassis Manager 
The chassis manager printed circuit board assembly (PCBA) is a general-purpose 
processing assembly integrated into the plenum of the chassis and attaching directly 
to the Power Distribution Backplane (PDB).  The chassis manager communicates 
directly with the server blades and provides management for all devices within the 
rack, including power supplies and fans. Figure 1 shows a CAD representation of the 
chassis manager. 



Open Compute Project  Open CloudServer chassis management specification 
http://opencompute.org 7 
 
Figure 1. CAD representation of the chassis manager 
5.1 Features 
The chassis manager features include: 
 Input/Output (I/O): 
o 2 x 1GbE Ethernet (general purpose to be used for network access or for 
direct connector to the top-of-rack [TOR] management ports) 
o 4 x RS-232 (network switch management for boot strap initial start-up) 
o Remote power control (one input signal, three output signals to the power 
distribution unit [PDU] or to another chassis manager for remote power 
control) 
 Windows Server 2012 operating system 
 Hot repair, no downtime during replacement 
 Server hardware 
o Embedded x86 processor 
o Memory—4GB with error-correcting code (ECC) 
o Storage—64GB solid-state drive (SSD) 
o Trusted Platform Module—enabling a secure solution 
o Embedded serial multiplexor for hard-wired communication to blades 
o Blade power on/off signals hard-wired for definitive control of blade power 


 
8 January 28, 2014 
Figure 2 shows a top-level representation of the chassis manager, trays, power 
supply units, and fans. 
Chassis Management
General purpose and highly flexible
Chassis        
Fan Tray
PSUs
1 .. 6
Tray
1 .. 12
Chassis Manager
Windows Server 2012
Serial Management
Power Control
PSU Monitoring
Fan Control and Monitoring
2 x 1GbE
General 
Purpose
4 x RS232
NWK Switch 
Management
Power Control
3 x Outputs
1 x Input
 
Figure 2. Top level representation of chassis manager 
Figure 3 shows the hardware block diagram for the chassis manager. 



Open Compute Project  Open CloudServer chassis management specification 
http://opencompute.org 9 
  Chassis Manager  (CM)
Tray1_Blade_EN[3:0]
Tray2_Blade_EN[3:0]
Tray3_Blade_EN[3:0]
Tray4_Blade_EN[3:0]
Fan PWM
CMC_Fan Tach[4:1]
Fan Ctl 
ADT740
0x5Eh
6 PSU 
6 PSU 
6 PSU 
6 PSU 
6 PSU 
6 Fans
Tray5_Blade_EN[3:0]
Tray6_Blade_EN[3:0]
Tray7_Blade_EN[3:0]
Tray8_Blade_EN[3:0]
Tray9_Blade_EN[3:0]
Tray10_Blade_EN[3:0]
Tray11_Blade_EN[3:0]
Tray12_Blade_EN[3:0]
PCA9535C
GPIO
0x40h
PCA9535C
GPIO
0x42h
PCA9535C
GPIO
0x44h
X86 SoC
CM FRU EEPROM
0xA0h
 Fan Ctl 
ADT7470
0x58h
CMC_Fan Tach[5:6]
CPLD_3
Altera
EPM240
1
2
 
23
24
          RST   RX/TX
Tray7_Node1_TX/RX
Tray7_Node2_TX/RX
Tray12_Node3_TX/RX
Tray12_Node4_TX/RX
PCA9535C
GPIO
0x48h
PCA9516
I2C Hub
PMBus1
6 PSU 
PSU 1..2
6 PSU 
PSU 3..4
6 PSU 
PSU 5..6
PMBus2
PMBus3
AC_OK[6:1]
DC_OK[6:1]
Attention LED
Status LED
PCA9535C
GPIO
0x4Ah
PSU_PS_ON[6:1]
PCA_CPLD_WDT2
Power Switch[2:0]
CPLD_FAN_MAX
CPLD_WDT[1,3]
WDT_ENABLE_N
UART_SW_S[0:5]_N
CMC_CPU_RST_N
CPLD_EXT_RST_N
CMC_RESERVE_1
FAN_MAX_CTR
CPLD_FAN_MAX
PMB_EN_[1:3]
CPLD_2
Altera
EPM240
1
2
 
23
24
RST   RX/TX              .
Tray1_Node1_TX/RX
Tray1_Node2_TX/RX
Tray6_Node3_TX/RX
Tray6_Node4_TX/RX
WDT_LED
PSU_ALERT_N
CPLD_THRMTRIP_LOG_N
PCA9535_INT_N
SC18IM700
(RS232 to I2C)
PMB_EN_1
PMB_EN_2
PMB_EN_3
PCA9535_INT_N
FAN_MAX_CTR
CPLD_WDT_1
CPU_RST_N
CMC_RESERVE_1
GPIO0
GPIO1
GPIO2
GPIO3
GPIO4
GPIO5
GPIO6
GPIO7
RST#          TX/RX
I2C
SC18IM700
(Serial Mux Ctrl)
GPIO0
GPIO1
GPIO2
GPIO3
GPIO4
GPIO5
GPIO6
GPIO7
RST#          TX/RX
 UART_SW_S0_N
UART_SW_S1_N
UART_SW_S2_N
UART_SW_S3_N
UART_SW_S4_N
UART_SW_S5_N
WDT_EN_N
CABLE_DETECT_N
COM4
TX/RX
RI
RTS
DTR
PDB
1GbE
RJ45
(metal)
COM1 
RJ45 
(plastic)
COM2 
RJ45 
(plastic)
COM5 
RJ45 
(plastic)
1GbE
RJ45
(metal)
COM6 
RJ45 
(plastic)
ON/OFF 
output
ON/OFF 
CM input
ON/OFF 
output
ON/OFF 
ouput
COM3RI
RTS
DTR
TX/RX
 
Figure 3. Chassis manager hardware block diagram 



 
10 January 28, 2014 
 
5.2 Signal Interface 
The chassis manager interfaces to the power distribution board through two PCIe 
x16 connectors. Table 1 and Table 2 show the pinout information for these 
connectors. Refer to the schematics for connector reference designators. 
 
Table 1. PDB Interface Connector (J18) 
Pin Signal Pin Signal 
B1 GND A1 GND 
B2 LAN2_P1_P A2 GND 
B3 LAN2_P1_N A3 LAN2_P3_P 
B4 GND A4 LAN2_P3_N 
B5 LAN2_P2_P A5 GND 
B6 LAN2_P2_N A6 LAN2_P4_P 
B7 GND A7 LAN2_P4_N 
B8 GND A8 GND 
B9 GND A9 POWER_SW3_PWR_CTR_12V 
B10 I2C_PDB_SCL A10 POWER_SW2_PWR_CTR_12V 
B11 I2C_PDB_SDA A11 POWER_SW1_PWR_CTR_12V 
B12 P3V3_NODE1 A12 NC 
B13 NC A13 NC 
B14 NC A14 NC 
B15 NC A15 NC 
B16 NC A16 NC 
B17 NC A17 GND 
B18 GND A18 UART_RTS_RP6_L_N 
B19 UART_RTS_RP5_L_N A19 UART_DSR_RP6_L_N 
B20 UART_DSR_RP5_L A20 UART_RX_RP6_L 
B21 UART_RX_RP5_L A21 UART_TX_RP6_L 
B22 UART_TX_RP5_L A22 UART_DTR_RP6_L_N 
B23 UART_DTR_RP5_L_N A23 UART_CTS_RP6_L 
B24 UART_CTS_RP5_L_N A24 UART_RI_RP6_L_N 
B25 UART_RI_RP5_L_N A25 GND 



Open Compute Project  Open CloudServer chassis management specification 
http://opencompute.org 11 
Pin Signal Pin Signal 
B26 GND A26 FAN4_TACH 
B27 FAN1_TACH A27 FAN5_TACH 
B28 FAN2_TACH A28 FAN6_TACH 
B29 FAN3_TACH A29 GND 
B30 GND A30 FAN_PWM 
B31 T12_NODE1_EN A31 GND 
B32 T12_NODE2_EN A32 I2C_PSU3_SCL 
B33 T12_NODE3_EN A33 I2C_PSU3_SDA 
B34 T12_NODE4_EN A34 GND 
B35 GND A35 T11_NODE1_EN 
B36 UART_T12_NODE1XD A36 T11_NODE2_EN 
B37 UART_T12_NODE1_TXD A37 T11_NODE3_EN 
B38 UART_T12_NODE2_RXD A38 T11_NODE4_EN 
B39 UART_T12_NODE2_TXD A39 GND 
B40 GND A40 UART_T11_NODE1_RXD 
B41 UART_T12_NODE3_RXD A41 UART_T11_NODE1_TXD 
B42 UART_T12_NODE3_TXD A42 UART_T11_NODE2_RXD 
B43 UART_T12_NODE4_RXD A43 UART_T11_NODE2_TXD 
B44 UART_T12_NODE4_TXD A44 GND 
B45 GND A45 UART_T11_NODE3_RXD 
B46 T10_NODE1_EN A46 UART_T11_NODE3_TXD 
B47 T10_NODE2_EN A47 UART_T11_NODE4_RXD 
B48 T10_NODE3_EN A48 UART_T11_NODE4_TXD 
B49 T10_NODE4_EN A49 GND 
B50 GND A50 T9_NODE1_EN 
B51 UART_T10_NODE1_RXD A51 T9_NODE2_EN 
B52 UART_T10_NODE1_TXD A52 T9_NODE3_EN 
B53 UART_T10_NODE2_RXD A53 T9_NODE4_EN 
B54 UART_T10_NODE2_TXD A54 GND 
B55 GND A55 UART_T9_NODE1_RXD 
B56 UART_T10_NODE3_RXD A56 UART_T9_NODE1_TXD 
B57 UART_T10_NODE3_TXD A57 UART_T9_NODE2_RXD 
B58 UART_T10_NODE4_RXD A58 UART_T9_NODE2_TXD 
B59 UART_T10_NODE4_TXD A59 GND 
B60 GND A60 UART_T9_NODE3_RXD 



 
12 January 28, 2014 
Pin Signal Pin Signal 
B61 T8_NODE1_EN A61 UART_T9_NODE3_TXD 
B62 T8_NODE2_EN A62 UART_T9_NODE4_RXD 
B63 T8_NODE3_EN A63 UART_T9_NODE4_TXD 
B64 T8_NODE4_EN A64 GND 
B65 GND A65 T7_NODE1_EN 
B66 UART_T8_NODE1_RXD A66 T7_NODE2_EN 
B67 UART_T8_NODE1_TXD A67 T7_NODE3_EN 
B68 UART_T8_NODE2_RXD A68 T7_NODE4_EN 
B69 UART_T8_NODE2_TXD A69 GND 
B70 GND A70 UART_T7_NODE1_RXD 
B71 UART_T8_NODE3_RXD A71 UART_T7_NODE1_TXD 
B72 UART_T8_NODE3_TXD A72 UART_T7_NODE2_RXD 
B73 UART_T8_NODE4_RXD A73 UART_T7_NODE2_TXD 
B74 UART_T8_NODE4_TXD A74 GND 
B75 GND A75 UART_T7_NODE3_RXD 
B76 T6_NODE1_EN A76 UART_T7_NODE3_TXD 
B77 T6_NODE2_EN A77 UART_T7_NODE4_RXD 
B78 T6_NODE3_EN A78 UART_T7_NODE4_TXD 
B79 T6_NODE4_EN A79 GND 
B80 GND A80 PSU_ALERT_R_N 
B81 UART_T6_NODE1_RXD A81 T5_NODE1_EN 
B82 UART_T6_NODE1_TXD A82 T5_NODE2_EN 
 
Table 2. PDB Connector Interface (J35) 
Pin Signal Pin Signal 
B1 GND A1 GND 
B2 UART_T6_NODE2_RXD A2 T5_NODE3_EN 
B3 UART_T6_NODE2_TXD A3 T5_NODE4_EN 
B4 GND A4 GND 
B5 UART_T6_NODE3_RXD A5 UART_T5_NODE1_RXD 
B6 UART_T6_NODE3_TXD A6 UART_T5_NODE1_TXD 
B7 UART_T6_NODE4_RXD A7 GND 
B8 UART_T6_NODE4_TXD A8 UART_T5_NODE2_RXD 
B9 GND A9 UART_T5_NODE2_TXD 



Open Compute Project  Open CloudServer chassis management specification 
http://opencompute.org 13 
Pin Signal Pin Signal 
B10 I2C_PSU2_SCL A10 UART_T5_NODE3_RXD 
B11 I2C_PSU2_SDA A11 UART_T5_NODE3_TXD 
B12 T4_NODE1_EN A12 UART_T5_NODE4_RXD 
B13 T4_NODE2_EN A13 UART_T5_NODE4_TXD 
B14 T4_NODE3_EN A14 GND 
B15 T4_NODE4_EN A15 T3_NODE1_EN 
B16 GND A16 T3_NODE2_EN 
B17 UART_T4_NODE1_RXD A17 T3_NODE3_EN 
B18 UART_T4_NODE1_TXD A18 T3_NODE4_EN 
B19 UART_T4_NODE2_RXD A19 GND 
B20 UART_T4_NODE2_TXD A20 UART_T3_NODE1_RXD 
B21 GND A21 UART_T3_NODE1_TXD 
B22 UART_T4_NODE3_RXD A22 UART_T3_NODE2_RXD 
B23 UART_T4_NODE3_TXD A23 UART_T3_NODE2_TXD 
B24 UART_T4_NODE4_RXD A24 GND 
B25 UART_T4_NODE4_TXD A25 UART_T3_NODE3_RXD 
B26 GND A26 UART_T3_NODE3_TXD 
B27 T2_NODE1_EN A27 UART_T3_NODE4_RXD 
B28 T2_NODE2_EN A28 UART_T3_NODE4_TXD 
B29 T2_NODE3_EN A29 GND 
B30 T2_NODE4_EN A30 T1_NODE1_EN 
B31 GND A31 T1_NODE2_EN 
B32 UART_T2_NODE1_RXD A32 T1_NODE3_EN 
B33 UART_T2_NODE1_TXD A33 T1_NODE4_EN 
B34 UART_T2_NODE2_RXD A34 GND 
B35 UART_T2_NODE2_TXD A35 UART_T1_NODE2_RXD 
B36 GND A36 UART_T1_NODE2_TXD 
B37 UART_T2_NODE3_RXD A37 UART_T1_NODE3_RXD 
B38 UART_T2_NODE3_TXD A38 UART_T1_NODE3_TXD 
B39 UART_T2_NODE4_RXD A39 GND 
B40 UART_T2_NODE4_TXD A40 UART_T1_NODE4_RXD 
B41 GND A41 UART_T1_NODE4_TXD 
B42 I2C_PSU1_SCL A42 UART_T1_NODE1_RXD 
B43 I2C_PSU1_SDA A43 UART_T1_NODE1_TXD 
B44 GND A44 GND 



 
14 January 28, 2014 
Pin Signal Pin Signal 
B45 PSU1_AC_OK A45 PSU1_DC_OK 
B46 PSU2_AC_OK A46 PSU2_DC_OK 
B47 PSU3_AC_OK A47 PSU3_DC_OK 
B48 PSU4_AC_OK A48 PSU4_DC_OK 
B49 PSU5_AC_OK A49 PSU5_DC_OK 
B50 PSU6_AC_OK A50 PSU6_DC_OK 
B51 GND A51 GND 
B52 UART_RTS_P5_L_N A52 UART_RTS_P6_L_N 
B53 UART_DSR_P5_L_N A53 UART_DSR_P6_L_N 
B54 UART_RX_P5_L A54 UART_RX_P6_L 
B55 UART_TX_P5_L A55 UART_TX_P6_L 
B56 UART_DTR_P5_L_N A56 UART_DTR_P6_L_N 
B57 UART_CTS_P5_L_N A57 UART_CTS_P6_L_N 
B58 UART_RI_P5_L_N A58 UART_RI_P6_L_N 
B59 GND A59 GND 
B60 UART_RTS_P1_L_N A60 UART_RTS_P2_L_N 
B61 UART_DSR_P1_L_N A61 UART_DSR_P2_L_N 
B62 UART_RX_P1_L A62 UART_RX_P2_L 
B63 UART_TX_P1_L A63 UART_TX_P2_L 
B64 UART_DTR_P1_L_N A64 UART_DTR_P2_L_N 
B65 UART_CTS_P1_L_N A65 UART_CTS_P2_L_N 
B66 GND A66 GND 
B67 NC A67 NC 
B68 NC A68 NC 
B69 NC A69 NC 
B70 NC A70 NC 
B71 GND A71 GND 
B72 LAN1_P3_P A72 LAN1_P1_P 
B73 LAN1_P3_N A73 LAN1_P1_N 
B74 GND A74 GND 
B75 LAN1_P4_P A75 LAN1_P2_P 
B76 LAN1_P4_N A76 LAN1_P2_N 
B77 GND A77 GND 
B78 CM_PWR_CTL_IN A78 P12V_PDB 



Open Compute Project  Open CloudServer chassis management specification 
http://opencompute.org 15 
Pin Signal Pin Signal 
B79 P12V_PDB A79 P12V_PDB 
B80 P12V_PDB A80 P12V_PDB 
B81 MATE_R_N A81 P12V_PDB 
B82 P12V_PDB A82 P12V_PDB 
5.3 Blade Management 
The chassis manager is connected to each blade via two blade enable signals and 
two serial connections. Figure 4 shows the blade management connectivity from the 
chassis manager to the blades via the power distribution board and tray backplane. 
CM
 PDB
C
O
M
4
UART4_TXD
UART4_RXD
M
U
X
UART_T[1:12]_
BLAD[1:4]_TX
UART_T[1:12]_
BLAD[1:4]_RD
CM CONN
CM CONN
UART_T[1:12]_
BLAD[1:4]_TX
UART_T[1:12]_
BLAD[1:4]_RD
PDB TRAY CONNECTOR
Motherboard
AIRMAX
BMC
NODE1_SIN
NODE1_SOUT
NODE2 for 
Debug Only
Blade1_EN
 In-Rush
Blade2_EN
+3.3V
Motherboard
AIRMAX
BMC
NODE1_SIN
NODE1_SOUT
NODE2 for 
Debug Only
Blade1_EN
 In-Rush
Blade2_EN
+3.3V
Tray Backplane
TRAY GOLD FINGER CONNECTOR
NODE1_TXD
NODE1_RXD
BLADE 1
NODE2_TXD
NODE2_RXD
NODE3_TXD
NODE3_RXD
NODE4_TXD
NODE4_RXD
NODE1_EN
NODE2_EN
BLADE 1
NODE3_EN
NODE4_EN
G
P
I
O
T[1:12]_BLAD[1:4]_TX
T[1:12]_
BLAD[1:4]_EN
Figure 4. Blade management connectivity 
5.4 Power Control 
The chassis manager provides controls for power of the blades and remote devices.  
At web-scale, definitive control over power is necessary to provide a clean reset in 
the event of locked-up or hung circuits. 
5.4.1 Blade Power Control 



 
16 January 28, 2014 
The blade enable signals indicate on/off to the in-rush controller on the blade to 
emulate a full power off. 
The blade enable signals are implemented via General Purpose I/O (GPIO) registers.  
The default is to float high via pull-ups on the blade, so that when the chassis 
manager is removed or when the power is cycled for service, blade operation is not 
disrupted. 
The signals are grouped to make it possible for all blades on a single tray to be 
powered on/off coincidently, and to let blades on different trays be powered on/off 
either coincidently or through timed power control. 
Timed power control can be used to control servers and JBODs (for example, to 
prevent incorrect errors from being reported when using a head server node and 
JBOD blades). The following steps can be used: 
1. Power off the head (server) node, and allow a short delay. 
2. Power off the JBOD blade, and allow a five second delay. 
3. Power on the JBOD blade, and allow a short delay.  
4. Power on the head (server) node. 
Timed delays can be easily adjusted to match the needs of the hardware and storage 
though the chassis manager. 
5.4.2 Remote Power Control 
It is important to have full power control over remote devices such as network 
switches or other chassis managers. 
The remote power controls are 12V on/off signals. The default is 0V (ON). Off is 12V, 
so that if a chassis manager is removed or if the power is cycled, remote device 
operation is not disrupted.   
The individual signals are: 
 ON/OFF input: accepts the 12V signal from a remote chassis manager for 
power control 
 Three ON/OFF outputs: allows control of remote devices 



Open Compute Project  Open CloudServer chassis management specification 
http://opencompute.org 17 
5.5 Communication Ports 
Table 3 lists the definition and translation of the serial COM port signals of the RJ-45 
connector for ports 1 and 2 (see Figure 3).  
These definitions match the functionality of switch consoles that use RJ-45, but can 
be used to select cables that convert from DB-9 or DB-25 connections. The system 
swaps received data/transmitted data (RxD/TxD), clear to send/request to send 
(CTS/RTS), and data terminal ready/data set ready (DTR/DSR) signals so a straight 
Ethernet cable can be used. 
Table 3. Serial RJ-45 Cable Definition for Ports 1 and 2 
PDB connection  
ports 1 and 2 Typical switch management port 
Signal on CM 
board RJ-45 connector pin RJ-45 connector pin Switch console port  
RTS 1 1 CTS 
DSR 2 2 DTR 
RxD 3 3 TxD 
GND 4 4 GND 
GND 5 5 GND 
TxD 6 6 RxD 
DTR 7 7 DSR 
CTS 8 8 RTS 
Table 4 lists the definition and translation of the serial COM port signals of the RJ-45 
connector for serial COM ports 5 and 6 (see Figure 3). COM port 3 and 4 are internal 
to the chassis manager board. 
Table 4. Serial RJ-45 Cable Definition for Ports 5 and 6 
PDB connection  
ports 5 and 6 Typical switch management port 
Signal on CM 
board RJ-45 connector pin RJ-45 connector pin Switch console port  
RTS 1 1 CTS 



 
18 January 28, 2014 
PDB connection  
ports 5 and 6 Typical switch management port 
Signal on CM 
board RJ-45 connector pin RJ-45 connector pin Switch console port  
DSR 2 2 DTR 
RxD 3 3 TxD 
RI 4 4 GND 
GND 5 5 GND 
TxD 6 6 RxD 
DTR 7 7 DSR 
CTS 8 8 RTS 
5.6 Mechanical Specifications 
Figure 5 shows the mechanical control outline for the chassis manager.  Also shown 
(circled in red) are the edge fingers that provide connectivity to the power 
distribution board. 



Open Compute Project  Open CloudServer chassis management specification 
http://opencompute.org 19 
 
Figure 5. Chassis manager dimensions and edge finger locations. 
5.7 Chassis LEDs 
Each chassis has two light-emitting diodes (LEDs) on the chassis manager: a health 
status LED that is green and an attention LED that is red. Both LEDs are driven by a 
single GPIO bit off the blade’s management i2c tree. 
5.7.1 Chassis Health Status LED 
The chassis health status LED indicates whether the chassis manager has booted. 
Note that if the 12V power is off, the LEDs on the power supplies are also off.  
Table 5 describes the operation of the chassis health status LED. 
Table 5. Chassis Health Status LED Description 
LED Status Condition 
Off 
 Backplane 12V power is off if power supply LEDs are off 
 Backplane 12V power is on, but chassis manager never booted if power supply 
LEDs are on 


 
20 January 28, 2014 
LED Status Condition 
Solid green on  Backplane 12V power is on and chassis manager has booted 
5.7.2 Chassis Attention LED 
The chassis attention LED is visible from the rear of the chassis without opening the 
fan tray. This LED directs service technicians to the correct chassis during repair. 
When possible, blade diagnostics are used to direct repairs; alternately, the scale-out 
management software can be used. In both cases, logs of the repair work are 
available.  
The chassis attention LED indicates the following conditions: 
 Operator directed 
An operator can manually set the chassis attention LED (for example, 
identification of chassis cables) 
 Power supply failure 
chassis manager has detected a power supply failure  
 Fan failure 
chassis manager has detected a fan failure 
Note that the chassis attention LED must be turned off after service is complete.  
Table 6 describes the operation of the chassis attention LED. 
Table 6. Chassis Attention LED Description 
LED Status Condition 
Off  No attention indicated 
Solid red 
 Operator directed 
 Power supply or fan failure 
6 Systems Management Operations 
The following sections describe the system management operations for the rack 
infrastructure, and for the in-band and out-of-band (OOB) management paths. 



Open Compute Project  Open CloudServer chassis management specification 
http://opencompute.org 21 
Systems management is designed to present a consistent, optimized interface. The 
chassis manager provides the front end through an applications interface (RESTful 
web API) for automated management and a CLI for manual management. The chassis 
manager manages all devices within the rack and communicates directly with the 
blade management system through a serial multiplexor. 
There are two possible paths for systems management: in-band and out-of-band.  
 The in-band management path is through the primary network interface card 
(NIC) while the operating system is running.  
  The out-of-band path is through the chassis manager.  
In-band is the preferred path for systems management whenever possible. 
6.1 Rack and Chassis Manager Commands 
The chassis manager is responsible for managing the blades and the infrastructure 
within the rack. It monitors the health of the power supplies and the fans and sets 
the fan speeds. Because the chassis manager is the gateway into the system, it also 
gathers all information necessary to perform wiring checks by identifying the nodes 
in each slot and identifying their media access control (MAC) addresses, the switches, 
and the cable MAC addresses. 
Table 7 lists the functionality of the commands that apply to the rack infrastructure. 
Table 7. Rack Infrastructure Command Functionality 
Requirement Details 
Switch power control 
(complete ON/OFF) 
Cycle the power to the switch (two 12V signals are driven by the 
chassis manager) 
Rack identification 
Provides an inventory of rack hardware: 
 Chassis manager information 
 Chassis numbers installed (part number, serial number) 
 Power supply unit and fan status 
Blade identification 
For every blade slot in every chassis: 
 Present 
 Type 
 Location and network connections 
 Network MAC addresses 
 Asset information (such as globally unique identifier [GUID]), 
device type, and versions) 
 Fan cubic feet per minute (CFM) requirement for each blade 



 
22 January 28, 2014 
Requirement Details 
Network identification 
For every network switch in the rack managed by the CM: 
 Status 
 GUID 
 Status and MAC addresses connected to each port 
Power supply unit (PSU), fan 
status 
 PSU DC-OK 
 AC-OK 
 Fan tachometer 
 Fan setting 
Fan speed control  Required fan speed 
Chassis power consumption For use with advanced power capping, integration with rack-level 
uninterrupted power supply (UPS), high temperature operation 
Manageability firmware update  To update microcontrollers within the chassis through the CM   
 To update PSU and fan control firmware, if applicable 
User management 
 Security privilege levels for users connected to the CM (for 
example, not all users logged into the CM will be able control 
fan speed or powering blades ON/OFF)   
 Security privilege mechanisms are still TBD 
6.2 In-Band Management Commands 
The primary method for managing servers is in-band through the operating system.  
The system can use a unified extensible firmware interface (UEFI) that allows more 
functionality through the primary NIC, though this is not considered to be in-band 
and is not mandatory for interoperability. UEFI can initialize the NIC very early in the 
boot sequence, and can implement serial-over-local area network (SOL) to 
complement Windows 8 SOL support for system debug. 
The path through the operating system uses the native Windows intelligent platform 
management interface (IPMI) driver and native IPMI Windows management 
instrumentation (WMI) provider. The baseboard management controller (BMC) 
firmware must be compatible with the native Windows IPMI keyboard controller style 
(KCS) interface driver.  
A number of functions are implemented with a utility that is traditionally run under 
the operating system; these utilities could be run under UEFI (method to be 
determined).   



Open Compute Project  Open CloudServer chassis management specification 
http://opencompute.org 23 
Table 8 lists command functionality that is supported by the in-band path. Note that 
it is assumed that a hardware monitoring device (HMD) will be present on the 
motherboard to provide management functionality. 
Table 8. Command Functionality Supported by In-Band Path 
Function Method Function details 
Identification WMI 
 HMD ID/version information 
 System GUID 
 HMD MAC address (only if sideband LAN access is 
provided) 
 Server MAC address 
 Asset tag 
Chassis power WMI 
 Power ON 
 Power OFF 
 Warm reset 
Console 
Windows 8 and 
UEFI SOL, Chassis 
Manager 
 Serial console 
Basic input/output 
system (BIOS) 
firmware update 
Utility  Motherboard flash 
Manageability 
firmware update Utility  Motherboard flash 
Host configuration 
BIOS settings Utility 
 Boot order 
 Power policy 
 Real-time clock 
Event logging WMI 
 Get log in IPMI SEL format 
 Clear log 
 Logs for AP/FC remote management agent (RMA) 
diagnosis and ticketing 
Temperature 
monitoring WMI 
 Inlet  
 Exhaust 
 CPU temperature 
Power management WMI 
 Set power limit 
 Get power limit 
 Get power reading 
Performance/power 
state WMI  Power capping 



 
24 January 28, 2014 
Function Method Function details 
Failure and wear 
indicators WMI 
Includes HDD and SSD self-monitoring, analysis and 
reporting technology (SMART) data, memory error logs, 
and more 
6.3 Out-of-Band Management Commands 
A few server management functions use the out-of-band management path through 
the serial link that is connected to the ME or HMD.   
Table 9 lists the blade management command functionality that is supported by out-
of-band path. 
Table 9. Command Functionality Supported by Out-of-Band Path 
Function Function details Descriptions 
Identification 
 HMD MAC address 
 Server MAC address 
 Asset tag 
 MAC addresses used for discovery and wiring 
checks 
 Asset tag is used for tax compliance audits 
Blade node 
power 
 Hard power ON 
 Hard power OFF 
 Drives the Blade_EN to the in-rush controller to 
perform full power ON/OFF  
 OFF also turns off power to the ME/HMD 
Blade node 
power 
 Soft power ON 
 Soft power OFF 
 Warm reset 
 Under direction of the ME or HMD 
Event logging 
 Power status 
(ON/OFF/sleep) 
 Health status (healthy/error) 
 Fan/CFM request 
 Provides at-a-glance status of server 
 Fan/CFM information is polled every 10 seconds 
7 Chassis Manager Services 
Figure 6 shows the services that the chassis manager provides. 



Open Compute Project  Open CloudServer chassis management specification 
http://opencompute.org 25 
 
Figure 6. Chassis manager services 
Table 10 lists the chassis manager services, and the sections that follow provide 
additional description. 
Table 10. Chassis manager services 
Chassis manager 
service Description 
Fan service 
Controls the fan speed of all the fans housed in the chassis to keep the 
servers cool and operational 
Checks the status of every fan and alerts when a fan speed becomes 
unrealistic 
PSU service 
Reads the status of every power supply unit (PSU) in the chassis and sends an 
alert if a PSU goes down or malfunctions 
Reports power reading for every PSU  
Power control service Provides the service to power ON/OFF every blade in the chassis 
Blade management 
service 
Provides the following blade management services:  
 Chassis power management (ON/OFF/reset) 
 Field replaceable unit (FRU) management 
 Sensor management 
 Serial console redirection 
 Blade ID (through LED) 


 
26 January 28, 2014 
Chassis manager 
service Description 
Top-of-rack (TOR) 
service 
Provides a serial connection to the TOR and acts as a gateway to all serial 
communication to the TOR 
Security Allows for creating users, deleting users, and updating user properties such as 
passwords 
Chassis manager 
control services 
Exposes commands to manage the chassis manager itself (for example, NIC 
settings of the NIC ports) 
7.1 Fan Control Protocol 
This section describes the fan control protocol, and provides an example for 
calculating the pulse-width modulation (PWM) sensor reading. 
Table 11 lists the input and output for the fan control software. 
Table 11. Input and Output for Fan Control Software 
Description 
Input  PWM sensor reading from each blade 
 Time period for sampling 
Output  Fan PWM for setting fan speed for the entire chassis 
7.1.1 Determining Fan Speed 
The chassis manager uses the following steps to determine the fan speed: 
1. Get PWM sensor values from the blade (see the example in the section that 
follows). 
a. The IPMI Get Sensor Reading command is used to get the PWM sensor 
values from the blade. Note that the PWM sensor ID is 1. (This sensor should 
also be the first sensor enumerated in the IPMI sensor data record [SDR].) 
b. This sensor reading is sampled for each blade periodically; this time period is 
determined by the configuration parameter when the chassis manager starts 
(currently this configuration parameter is set by default to 10 seconds, which 
means each blade is polled exactly every 10 seconds). 
2. Set PWM value as fan speed. 



Open Compute Project  Open CloudServer chassis management specification 
http://opencompute.org 27 
a. The chassis manager identifies the maximum value from all its constituent 
blade PWM values, and then sets the fan PWM to that value. Note that 
currently all the fans are set to the same speed. 
3. Correct for altitude. 
a. The fan speed is corrected for altitude using linear interpolation (see the 
hardware specification for more detail). 
b. Current altitude is obtained from the configuration file; if no altitude is 
present, this correction is not performed. 
4. Correct for one fan failure if necessary. 
a. If there is one fan failure, the PWM calculated from step 2 is scaled with the 
multiplier (maximum number of fans)/(maximum number of fans - 1). 
b. This linear scaling of fan PWM requested (within maximum limit of 100) is 
sufficient to handle one fan failure. 
c. The chassis manager also logs an error and sets the attention LED. 
5. Correct for more than one fan failure if necessary. 
a. If there is more than one fan failure, the chassis manager sets the fan speed 
to maximum PWM (100). It also logs an error and sets the attention LED. 
7.1.2 Sample PWM Calculation 
Following is an example of calculating the blade PWM sensor ID. This value should 
be exposed as a logical IPMI sensor with a lower limit of 20 and an upper limit of 
100. 
The algorithm is based on a feedback control loop that checks every sensor on the 
list (specified as priority level 1 to N) against a target specified by the component 
manufacturer for maximum reliability. The algorithm then computes the relative PWM 
increase or decrease required and sends this value to the blade. 
Table 12 lists the input and output for the main algorithm. 
Table 12. Input and Output for Fan Control Software 
Description 



 
28 January 28, 2014 
Input 
 Sensor priority 
 Sensor target 
Output 
 PWM value 
 Increase/decrease request 
Following is the pseudocode for the process: 
1. Create a sensor reading table T[1..N]. See Table 13 for the example. 
2. For each sensor (with priority 1..N), run the following statements: 
  If (sensor.currentValue != sensor.target) 
   Difference = sensor.currentvalue - sensor.target 
   PWMstep = ExponentialFunction(Step, Difference) 
   Input PWMstep into table location T[sensor.priority] 
  EndIf 
EndDo 
3. Find the maximum value from table T[1..N], and supply the absolute PWM value 
and a code that specifies whether to decrease or increase the PWM (based on 
negative or positive difference value) as part of the response packet.  
The function ExponentialFunction(step, difference) enables the decrease or increase in 
PWM based on distance from the target value. If the current value is very close to 
target value, the exponential function will return smaller step; if the current value is 
very far away from target value, the exponential function will return larger step. This 
keeps decay slow and controls linear swings between extremes. The exponential 
function is tuned specifically for each sensor. 
If none of the sensor values are valid, then the appropriate PWM should be 
determined by the blade vendor (this could be maximum or minimum PWM based 
on thermal profiles). Note that if the current temperature is higher than the high 
temperature, the PWM value is reset to “Max PWM.” 
The inlet temperature sensor is treated differently from the other sensors. It is used 
to define a base fan speed relative to the intake temperature to provide cooling for 
all components that are not directly monitored, and should ramp fan speeds up with 
inlet temperature increases as appropriate.  
Table 13 shows an example of a sensor reading table. 



Open Compute Project  Open CloudServer chassis management specification 
http://opencompute.org 29 
Table 13. Example Sensor Readings 
Sensor Target High critical Priority 
Inlet 30-55 38 1 
CPU 2 (downstream) 74 90 2 
CPU 1 74 90 3 
HDD 3 (downstream) 40 60 4 
HDD 4 (downstream) 40 60 5 
HDD 1 40 60 6 
HDD 2 40 60 7 
PCH 90 95 8 
DIMM 10 (downstream) 80 90 9 
DIMM 11 (downstream) 80 90 10 
DIMM 12 (downstream) 80 90 11 
DIMM 13 (downstream) 80 90 12 
DIMM 14 (downstream) 80 90 13 
DIMM 15 (downstream) 80 90 14 
DIMM 16 (downstream) 80 90 15 
DIMM 9 (downstream) 80 90 16 
DIMM 1 80 90 17 
DIMM 2 80 90 18 
DIMM 3 80 90 19 
DIMM 4 80 90 20 
DIMM 5 80 90 21 
DIMM 6 80 90 22 
DIMM 7 80 90 23 
DIMM 8 80 90 24 
The chassis manager polls all these PWM values from each individual blade, 
computes the maximum, and sets the fan speed accordingly. 



 
30 January 28, 2014 
7.2 Blade State Management 
The chassis manager needs to keep track of the state of all its blades to discover 
new blades and to optimize the code behavior. For example, if only one out of N 
blades is powered on, the chassis manager should not try to get sensor readings 
from the rest of the blades because the sensor-read command is time consuming.  
Figure 7 lists states and transitions for managing the blades. The chassis manager 
maintains these values for blades it controls.  
 
Figure 7. Blade state management 
Note that there are only two user-facing commands that can change the state of the 
blade: power ON and power OFF (Blade Enable ON and Blade Enable OFF) 
commands. IPMI commands are not part of the blade state because they are served 
in operational states (probation and healthy states. See Table 14 for more detail.  
Table 14. Blade States 
Blade state Description 


Open Compute Project  Open CloudServer chassis management specification 
http://opencompute.org 31 
Blade state Description 
Initialize (I) 
Captures the blade initialization steps when chassis manager starts or when a new 
blade is inserted.  
Creates client objects and of obtains IPMI session authentication, the GUID of the 
blade, and the SDR, which supplies the low and high threshold values for the fan 
algorithm.  
Checks the power enable status of the blade and moves the blade to:  
 Blade Enable Off (PEoff) if the blade is set to OFF 
 Probation (P) if initialization succeeds 
 Fail (F) if initialization does not succeed 
Blade Enable 
OFF (PEoff) 
Captures the state where the blade enable is off.  
All commands fail in this state except power ON.  
Periodically checks the power enable state to see if it is still in Blade Enable OFF. 
Probation (P) 
Transitory state that logically separates the operational states, making it possible 
to use a light-weight “get GUID” command as the heartbeat in the fail state.  
Prevents the fail count from being reset (catching “Get GUID” success and read 
sensor failure event loops).  
Chassis manager tries to serve one sensor read request in this state; if that 
succeeds, it moves to the healthy state. 
Healthy (H) 
Most blades should be in this state; transition to fail only when all temperature 
sensor reads fail 
Keep serving IPMI requests 
Fail (F) 
Non-operational, cannot serve any requests 
Increment fail count every time state is encountered from outside or through self-
loops 
At each iteration, try to get GUID with light-weight heartbeat: 
 If heartbeat succeeds and GUID has changed, re-initialize client 
 If heartbeat succeeds and GUID has not changed, blade moves to probation 
and back to healthy 
Note that if the fail count goes beyond a maximum (fail count > max), tries an 
initialization action for IPMI; this prevents infinite loops and discovers newly 
inserted blades 
7.3 Chassis Manager Component Failure Scenarios 
The chassis manager handles only fan failures: 
 Single fan failure:  
The chassis manager logs an error, sets fan speed to 6/5, and turns on the 
attention LED. 



 
32 January 28, 2014 
 Two or more fan failures:  
The chassis manager logs an error, sets fan speed to high, and turns on the 
attention LED. 
For all other failures, the chassis manager only logs an error and turns on the 
attention LED; by design, the chassis manager takes no pre-emptive action (for 
example, no action other than logging the error and turning on the attention LED is 
taken for PSU or blade-specific failures).  
8 Chassis Manager/Blade API 
The chassis manager/blade protocol is a small subset of the intelligent platform 
management interface (IPMI2.0) protocol. IPMI2.0 is therefore not required for the 
blade and chassis manager to communicate; only message format compatibility with 
IPMI2.0 is required.   
The chassis manager communicates with the target blade BMC firmware using IPMI 
basic mode over the IPMI Serial/Modem Interface (Reference: IPMI 2.0—14.4 Basic 
Mode). 
Note: For the purpose of completeness, this document contains abstracts and 
references to the IPMI 2.0 specification 
http://www.intel.com/content/www/us/en/servers/ipmi/ipmi-home.html and to the 
DCMI 1.5 specification http://www.intel.com/content/www/us/en/data-
center/dcmi/data-center-manageability-interface.html. References to these 
documents are not subject to the Microsoft OWF CLA 1.0 commitment for this 
specification.  
Table 15 lists the IPMI commands that are required or optional for compute blades 
and storage blades. (Note that “M” is mandatory and “O” is optional.)  
Note: Storage blade command requirements differ from compute blade commands.  
Table 15. Required IPMI Commands for Blades 



Open Compute Project  Open CloudServer chassis management specification 
http://opencompute.org 33 
Command name Reference Type Fn Cmd Compute 
blade 
JBOD 
blade 
Get Device ID  20.1 App 06h 01h M M 
Get System GUID  22.14 App 06h 37h M M 
Get Channel 
Authentication 
Capabilities 
22.13 App 06h 38h M M 
Get Session 
Challenge  22.16 App 06h 39h M N/A 
Activate Session  22.17 App 06h 3Ah M N/A 
Set Session Privilege 
Level  22.18 App 06h 3Bh M N/A 
Close Session  22.19 App 06h 3Ch M N/A 
Set Channel Access  22.22 App 06h 40h M N/A 
Get Channel Access  22.23 App 06h 41h M N/A 
Set User Access 
Command  22.26 App 06h 43h M N/A 
Get User Access 
Command  22.27 App 06h 44h M N/A 
Set User Name  22.28 App 06h 45h M N/A 
Get User Name 
Command  22.29 App 06h 46h M N/A 
Set User Password 
Command  22.3 App 06h 47h M N/A 
Get Chassis Status  28.2 Chassis 00h 01h M M 
Chassis Control  28.3 Chassis 00h 02h M N/A 
Chassis Identify  28.5 Chassis 00h 04h M N/A 
Set Power Restore 
Policy  28.8 Chassis 00h 06h M N/A 
Set Power Cycle 
Interval  28.9 Chassis 00h 0Bh M N/A 
Get System Restart 
Cause  28.11 Chassis 00h 07h M N/A 
Set System Boot 
Options  28.12 Chassis 00h 08h M N/A 



 
34 January 28, 2014 
Command name Reference Type Fn Cmd Compute 
blade 
JBOD 
blade 
Get System Boot 
Options  28.13 Chassis 00h 09h M N/A 
Get Sensor Reading 
Factors  35.5 Sensor 04h 23h M N/A 
Get Sensor Threshold  35.9 Sensor 04h 27h M N/A 
Get Sensor Reading  35.14 Sensor 04h 2Dh M N/A 
Read FRU Data  34.2 Storage 0Ah 11h M M 
Write FRU Data  34.3 Storage 0Ah 12h M M 
Get SDR Repository 
Info  33.9 Storage 0Ah 20h M N/A 
Reserve SDR 
Repository  33.11 Storage 0Ah 22h M N/A 
Get SDR  33.12 Storage 0Ah 23h M N/A 
Get SEL Info  31.2 Storage 0Ah 40h M N/A 
Reserve SEL  31.4 Storage 0Ah 42h M N/A 
Get SEL Entry  31.5 Storage 0Ah 43h M N/A 
Add SEL Entry  31.6 Storage 0Ah 44h M N/A 
Clear SEL  31.9 Storage 0Ah 47h M N/A 
Get SEL Time  31.10 Storage 0Ah 48h M N/A 
Set SEL Time  31.11 Storage 0Ah 49h M N/A 
Set Serial/Modem 
Configuration  25.1 Transport 0Ch 10h M N/A 
Get Serial/Modem 
Configuration  25.2 Transport 0Ch 11h M N/A 
Set Serial/Modem 
Mux  25.3 Transport 0Ch 12h M N/A 
Serial/Modem 
Connection Active  25.9 Transport 0Ch 18h M N/A 
Get Power Reading N/A DCMI 2Ch 02h M N/A 
Get Power Limit N/A DCMI 2Ch 03h M N/A 
Set Power Limit N/A DCMI 2Ch 04h M N/A 



Open Compute Project  Open CloudServer chassis management specification 
http://opencompute.org 35 
Command name Reference Type Fn Cmd Compute 
blade 
JBOD 
blade 
Activate Power Limit N/A DCMI 2Ch 05h M N/A 
Get Processor Info N/A OEM 30h 1Bh M N/A 
Get Memory Info N/A OEM 30h 1Dh M N/A 
Get PCIe Info N/A OEM 30h 44h M N/A 
Get Nic Info N/A OEM 30h 19h M N/A 
Get Disk Status N/A OEM 
Group 2Eh C4h N/A M 
Get Disk Info N/A OEM 
Group 2Eh C5h N/A M 
M = Mandatory, N/A = Not applicable to blade type 
8.1 Blade Implementation Requirements 
The following sections describe the blade implementation requirements. 
Only a small subset of commands of IPMI2.0 is required to work with the chassis 
manager. If a blade implements IPMI2.0 and conforms to the requirements described 
in the sections that follow, it is safe to assume that the blade is compatible with the 
chassis manager.  
8.1.1 Serial Port Timeout 
The serial line has a receiving transmission timeout of 100ms. The baseboard 
management controller (BMC) must therefore respond to all serial IPMI requests 
within 100ms. When it receives a response from the BMC, the chassis manager might 
immediately send another request. It is therefore possible that the BMC will receive 
multiple requests within a 100ms timeframe, depending on its response time. 
8.1.2 Session Timeout 
IPMI basic mode over a serial interface allows only one IPMI session. The IPMI 
session termination and timeout must be able to be configured with the Set 



 
36 January 28, 2014 
Serial/Modem Configuration command. The timeout period is set in 30 second 
increments. The termination command must allow inactivity timeout termination. 
8.1.3 BMC Serial Port Baud Rate 
The blade IPMI basic mode default serial port baud rate should be set to 115.2 kbps. 
The IPMI serial port baud rate must be able to be configured with the Set 
Serial/Modem Configuration command.  
8.1.4 Sensor Data Record  
The PWM sensor is the first sensor data record; however, if an alternative 
temperature sensor is preferred, this sensor can be the first sensor stored in the 
sensor data record. When enumerating the sensor data record, the first record 
accessed (0000) must always be the PWM or the alternative temperature sensor, 
depending on the PWM implementation. 
8.2 Request and Response Packet Formats 
Every request message from the chassis manager software has the format shown in 
Figure 8. 
rsAddress Function checksum rqAddress Seq cmd payload checksum
1 byte 1 byte 1 byte 1 byte 1 byte 1 byte n byte 1 byte
1 2 3 4 5 6 N N+1
 
Figure 8. Request packet format 
Every response from the chassis manager software to a request has the format 
shown in Figure 9. 



Open Compute Project  Open CloudServer chassis management specification 
http://opencompute.org 37 
rqAddress Function checksum rsAddress Seq cmd completion
code checksumpayload
1 byte 1 byte 1 byte 1 byte 1 byte 1 byte 1 byte n byte 1 byte
1 2 3 4 5 6 7 N N+1
 
Figure 9. Response packet format 
Table 16 provides details of the request and response packets. 
Table 16. Details for Request and Response Packets 
Number Packet Description 
1 rqAddress 
Requester's address, 1 byte 
Least-significant (LS) bit is 0 for slave addresses and 1 for software IDs  
Upper 7-bits hold slave address or software ID, respectively  
Byte is 20h when the BMC is the requester 
2 Function Function code   
Response function = request function +1 [debug identification] 
3 Checksum 
2's complement checksum of preceding bytes in the connection header  
8-bit checksum algorithm: initialize checksum to 0   
For each byte, checksum = (checksum + byte) modulo 256, then checksum 
= - checksum   
When the checksum and the bytes are added together, modulo 256, the 
result should be 0 
4 rsAddress 
Responder's slave address, 1 byte  
LS bit is 0 for slave addresses and 1 for software IDs  
Upper 7-bits hold slave address or software ID, respectively  
This byte is 20h when the BMC is the responder; the rqAddress will be the 
software ID from the corresponding request packet 
5 Seq Sequence number, generated by the requester 
6 Cmd Command byte 
7 Completion 
code 
Completion code returned in the response to indicated success/failure 
status of the request 
N Payload As required by the particular request or response for the command 



 
38 January 28, 2014 
Number Packet Description 
N+1 Checksum 
2's complement of bytes between the previous checksum   
8-bit checksum algorithm: Initialize checksum to 0   
For each byte, checksum = (checksum + byte) modulo 256, then checksum 
= - checksum   
When the checksum and the bytes are added together, modulo 256, the 
result should be 0 
8.3 Packet Framing 
Special characters are used to delimit the start and end of a command packet.  
Table 17 lists the packet framing characters. Note that the framing and data escape 
characters are applied after the message fields have been formatted.   
Table 17. Special Characters Used for Packet Framing 
Description Value 
Start character A0h 
Stop character A5h 
Packet handshake  A6h 
Data escape character AAh 
Message framing is similar to inter-integrated circuit (I2C) conditional framing, but 
replaced with start and stop characters and with the addition of a data byte escape 
character to ensure that the framing characters are not encountered within the body 
of the packet. The packet handshake character is used for implementing a level of 
software flow control with the remote application that is accessing the BMC. 
The start, stop, and escape characters are not allowed within the body of the 
message to make sure that the beginning and end of a message is unambiguously 
delimited. If a byte matching one of the special characters is encountered in the data 
to be transmitted, it is encoded into a corresponding two-character sequence for 
transmission. Table 18 summarizes these encoding sequences. 
Table 18. Encoding Sequences for Special Characters 
Data byte Encoded sequence 



Open Compute Project  Open CloudServer chassis management specification 
http://opencompute.org 39 
The first character of the sequence is always the escape character. Only the special 
characters plus the ASCII escape <ESC> character, 1Bh, are escaped. (Note that the 
ASCII escape <ESC> character, 1Bh, is escaped to let the BMC snoop for certain 
escape sequences in the data stream, such as the <ESC>( and <ESC>Q patterns.) All 
other byte values in the message are transmitted without escaping.  
When the packet is received, the process is reversed. If the two-byte escape 
sequence is detected in the packet, it is converted to the corresponding data-byte 
value. Note that the BMC will reject any messages that have illegal character 
combinations or that exceed message buffer length limits. The BMC may not send an 
error response for these conditions. 
The handshake character is used to signal that the BMC has freed space in its input 
buffers for a new incoming message. The BMC typically returns a handshake 
character within one millisecond of being able to accept a new message, unless the 
controller has already initiated a message transmission or an operation such as 
firmware update. Note that the handshake character is used in the system for flow 
control and error detection. Even if unauthenticated IPMI messages are being 
rejected (or dropped) by the BMC, the BMC is expected to respond with a handshake 
to indicate its buffers are ready for a new incoming message. 
Figure 10 shows the message payload encapsulated with the serial start and stop 
bytes. 
Request packet: 
rsAddress Function checksum rqAddress Seq cmd payload checksum
1 byte 1 byte 1 byte 1 byte 1 byte 1 byte n byte 1 byte
2 3 4 5 6 7 N N+1
Start 
(A0h)
1 byte
1
Stop
(A5h)
1 byte
N+2
 
A0h AAh (ESC), B0h 
A5h AAh (ESC), B5h 
AAh AAh (ESC), BAh 
A6h AAh (ESC), B6h 
1Bh <ESC> AAh (ESC), 3Bh 



 
40 January 28, 2014 
Response packet: 
rqAddress Function checksum rsAddress Seq cmd completion
code checksumpayload
1 byte 1 byte 1 byte 1 byte 1 byte 1 byte 1 byte n byte 1 byte
2 3 4 5 6 7 8 N N+1
Start 
(A0h)
1 byte
1
Stop
(A5h)
1 byte
N+2
 
Sample framed request packet 
Get Chassis Status Request
0xA02000E08104017AA5 
Sample Request
 
Sample framed response packet 
Chassis Status Response
0xA081047B20040100011000507AA5
Handshake
0xA6
100 ms0 ms
Sample Response
 
Figure 10. Message payload encapsulated with the serial start and stop bytes 
8.4 Serial Console Redirection 
To support serial console redirection, a blade should support serial port sharing. 
Serial port sharing is a mechanism in which the BMC controls logic that lets a serial 
controller on the baseboard and a serial controller for the BMC share a single serial 
connector. To support serial console redirection, the blade BMC should be able to 
switch serial port control to and from the system baseboard. 
Serial port sharing lets the IPMI basic mode messaging and system console 
redirection coexist on the same physical serial port. The BMC firmware should let the 
Set Serial/Modem Mux command switch the serial port from “BMC” to “SYS” for 
terminal console redirection. When the multiplexer (mux) is switched to the system 
(SYS), the firmware should snoop the in-bound traffic to detect IPMI message 
patterns (such as the IPMI Get Channel Authentication Capabilities and the Get 



Open Compute Project  Open CloudServer chassis management specification 
http://opencompute.org 41 
Session Challenge commands). If it detects an IPMI message pattern, the BMC 
firmware should take control of the serial port from the system and respond to the 
IPMI message. The BMC firmware should retain control of the serial port until it 
receives a new request to switch control of the serial port back to the system. 
When the BMC has control of the serial port, the messaging protocol should comply 
with the chassis manager API (see Open CloudServer chassis manager user interface 
specification). When in console redirection mode, the system should support VT100 
console output. 
Table 19 lists the conditions that determine the blade BMC behavior and the 
switching mechanism that enables the transitions between BMC messaging and 
console redirection. 
Table 19. Conditions Causing Switching 
Switching Conditions 
Switch to system 
 IPMI Set Serial/Modem Mux (to SYS) is received from either local area 
network (LAN) or serial 
 <ESC> Q is received from serial 
Switch to BMC 
 IPMI Set Serial/Modem Mux (to BMC) is received from LAN 
 The pattern "<ESC> (" is received over the serial console 
 The IPMI message pattern {0xA0, 0x20} is received over serial (this byte 
pattern represents the “start byte” framing character and the BMC address in 
a basic mode IPMI request message 
8.5 Chassis Manager Serial Port Session 
The chassis manager lets a client establish a serial port session to a target device (for 
example, a top of rack [TOR] network switch) that is physically connected to the 
chassis manager board. The chassis manager API provides four serial port session 
methods: StartSerialPortConsole, StopSerialPortConsole, SendSerialPortData, and 
ReceiveSerialPortData.  
Note that the serial port session API services devices attached to universal 
asynchronous receiver/transmitter (UART) 1, 2, 5, and 6. UART 4, which services blade 
devices populated in the chassis, uses a separate API. Note also that the ports 
allocated for the serial port session are COM 1, 2, 5, and 6.  



 
42 January 28, 2014 
Before attempting to communicate with the target device, the client should explicitly 
open a serial port session using StartSerialPortConsole with a parameter specifying 
the target serial port. The chassis manager will then attempt to open and initialize 
the target serial port. Currently, the serial baud rate supported for the serial port 
session is 9600 bps. When it receives the response for the StartSerialPortConsole 
request, the client must check the completion code to see if the serial port session 
has been successfully established. In addition, the client should use the session token 
stored in the response when issuing subsequent requests to the chassis manager 
throughout the session.  
When a serial port session has been successfully established, the client can issue 
commands to the target device using SendSerialPortData. The client can also receive 
data packets from the target device using ReceiveSerialPortData. Note that 
ReceiveSerialPortData is designed to operate asynchronously with 
SendSerialPortData, which means that the client can invoke ReceiveSerialPortData 
even if there is no preceding or matching invocation SendSerialPortData. The 
asynchronous design ensures that the client can reliably receive the data packets sent 
by the target device even without an explicit command (for example, console output 
messages generated while the target device is booting up). 
After all the packets of interest have been communicated, the client should explicitly 
close the session with StopSerialPortConsole. The chassis manager will then release 
the target serial port and make it available for other clients. 
8.6 Command-Completion Codes 
Table 20 lists the completion codes, follows the IPMI 2.0 completion codes. 
Table 20. Command-Completion Codes 
Code Description 
Generic completion codes (00h, C0h-FFh) 
00h   Command completed normally 
C0h  
 Node busy 
 Command could not be processed because command processing resources are 
temporarily unavailable 



Open Compute Project  Open CloudServer chassis management specification 
http://opencompute.org 43 
Code Description 
C1h  
 Invalid command  
 Used to indicate an unrecognized or unsupported command 
C2h   Command invalid for given logical unit number (LUN) 
C3h  
 Timeout while processing command 
 Response unavailable 
C4h  
 Out of space 
 Command could not be completed because of a lack of storage space required to 
execute the given command operation 
C5h   Reservation canceled or invalid reservation ID 
C6h   Request data truncated 
C7h   Request data length invalid 
C8h   Request data field length limit exceeded 
C9h  
 Parameter out of range 
 One or more parameters in the data field of the request are out of range (different 
from the invalid data field [CCh] code in that it indicates that the erroneous field(s) 
has a contiguous range of possible values) 
CAh   Cannot return number of requested data bytes 
CBh   Requested sensor, data, or record not present 
CCh   Invalid data field in request 
CDh   Command illegal for specified sensor or record type 
Ceh   Command response could not be provided 
CFh  
 Cannot execute duplicated request 
 This completion code is for devices which cannot return the response that was 
returned for the original instance of the request; such devices should provide 
separate commands that allow the completion status of the original request to be 
determined 
 An event receiver does not use this completion code, but returns the 00h completion 
code in the response to (valid) duplicated requests  
D0h   Command response could not be provided; SDR repository in update mode 
D1h   Command response could not be provided; device in firmware update mode 
D2h   Command response could not be provided; BMC initialization or initialization agent 
in progress 



 
44 January 28, 2014 
Code Description 
D3h  
 Destination unavailable; cannot deliver request to selected destination (for example, 
this code can be returned if a request message is targeted to SMS but the receive 
message queue reception is disabled for the particular channel) 
D4h   Cannot execute command due to insufficient privilege level or other security-based 
restriction (for example, disabled for firmware firewall) 
D5h  
 Cannot execute command 
 Command, or request parameter(s), not supported in present state 
D6h  
 Cannot execute command 
 Parameter is illegal because command sub -function has been disabled or is 
unavailable (for example, disabled for firmware firewall) 
FFh  Unspecified error 
Device-specific (OEM) codes (01h-7Eh) 
01h-7Eh  
 Device-specific (OEM) completion codes 
 This range is used for command-specific codes that are also specific to a particular 
device and version (prior knowledge of the device command set is required for 
interpretation) 
Command-specific codes (80h-BEh) 
80h-BEh  
 Standard command-specific codes 
 This range is reserved for command-specific completion codes for commands 
specified in this document 
8.7 Blade Command Payload 
The chassis manager protocol payload carries the blade commands, as shown in 
Figure 11. 
rqAddress
 Function
 checksum
 rsAddress
 Seq
 cmd
 completion
code
 checksum
payload
1 byte 1 byte 1 byte 1 byte 1 byte 1 byte 1 byte n byte 1 byte
2 3 4 5 6 7 8 N N+1
Start 
(A0h)
1 byte
1
Stop
(A5h)
1 byte
N+2
Payload
 
Figure 11. Chassis manager payload 



Open Compute Project  Open CloudServer chassis management specification 
http://opencompute.org 45 
Certain support commands are required for blade identification and session 
establishment. The following commands should always be accepted by the blade, 
whether sent outside of an active session or within the context of an active session: 
 Get System GUID  
 Get Channel Authentication Capabilities 
 Get Session Challenge 
 Activate Session 
8.7.1 Blade Identification Commands 
The Get Channel Authentication Capabilities command is used to identify the blade 
type (compute or “just a bunch of disks” [JBOD]). A blade should respond to this 
command before and after a session has been established. The response message 
should use byte 9 (OEM auxiliary data) to advertise the blade type: 0x04 for compute 
or 0x05 for storage. When response message byte 9 is combined with the OEM ID 
(bytes 6:8), the chassis manager will know both the OEM and type of blade.  
Compute blade implementations are required to support session-based 
authentication, while JBOD blades are not required to support-session based 
authentication. A blade advertises its authentication support through the Get 
Channel Authentication Capabilities command, byte 3 and byte 4. If a JBOD blade 
does not support authentication, then byte 3 and byte 4 should equal zero. If 
authentication is not supported on a JBOD blade, all mandatory (M) IPMI commands 
listed in this specification should be supported without a session initialization 
processes.    
Note that user session-based authentication is required for all system compute 
blades. Per-message-based authentication is not supported because session headers 
are not support over serial IPMI. 
8.7.2 Session Establishment Commands 
Before general messaging can occur, a session must be activated through a set of 
session setup commands: Activate Session, Get Session Challenge, and Set Session 



 
46 January 28, 2014 
Privilege Level. These commands can be thought of as always being 
unauthenticated. Note that Activate Session is the first, and in some cases only, 
authenticated command for a session. Figure 12 shows the process. 
1
2
3
4
5
6
Get 
Session
Challenge, 
Rq
Get 
Session
Challenge, 
Rs
Activate 
Session, Rq
Activate 
Session, Rs
Session 
Privilege 
Level, Rq Session 
Privilege 
Level, Rs
Chassis
Manager
Sled
BMC
 
Figure 12. Session establishment process 
The following steps are used to establish a session: 
1. The chassis manager sends a Get Channel Authentication Capabilities to the 
blade to get information about the blade type and session authentication 
support.  
If sessions are supported, the chassis manager advances to step 2.   
If the blade is a sessionless JBOD (some JBOD blades require no authentication or 
session establishment), the chassis manager skips steps 2-7 during the 
initialization process. 



Open Compute Project  Open CloudServer chassis management specification 
http://opencompute.org 47 
2. The chassis manager sends a Get Session Challenge request to the BMC with an 
authentication type of “none” and a username that selects which set of user 
information should be used for the session (UserId 1). This is the only place 
where the username is used during the process.  
3. The BMC looks up the user information associated with the username. If the user 
is found and allowed access via the given channel, the BMC returns a Get 
Session Challenge response that includes a randomly generated challenge string 
and a temporary session ID. The BMC keeps track of the username associated 
with the session ID; the session ID is used to look up the user’s information in 
step 4.  
4. The chassis manager then issues an Activate Session request. The request 
contains the temporary session ID plus the authentication information (None). 
(For example, the serial/modem connection might only pass a simple clear-text 
password in the activate session data.) The authentication format for different 
authentication types is specified in the description of the Activate Session 
command. Note that the system specification only supports authentication type 
None (0x00).   
5. The BMC uses the temporary session ID to look up the information for the user 
identified in the Get Session Challenge request (for example, the user’s 
password/key data and a stored copy of the earlier challenge string) and uses it 
to verify that the packet signature or password is correct.  
6. The chassis manager then sends a Set Session Privilege Level command to the 
BMC. This command is sent in authenticated format. After the session is activated, 
the session is set to an initial privilege level. A session that is activated is initially 
set to USER level, regardless of the maximum privilege level requested in the 
Activate Session command. The chassis manager must raise the privilege level of 
the session using this command to execute commands that require a higher level 
of privilege.   
7. The BMC looks up the privilege level set for the user. If the privilege level 
requested matches the level set for the user, the BMC responses to the chassis 
manager Set Session Privilege Level with a positive completion code. Note that 



 
48 January 28, 2014 
Set Session Privilege Level cannot be used to set a privilege level higher than 
the lowest of the privilege level set for the user. 
8.7.3 Session Termination 
If the blade BMC supports IPMI single-session serial connections and a session is 
established, the BMC should accept a Close Session command and immediately 
terminate the session, freeing up resources for another session to be established.  
If a session is not closed using Close Session, the session should time out and close 
itself after a specified time interval. This time interval should be configurable with the 
Set Serial/Modem Configuration command. (Note that the IPMI firmware should 
support all Set Serial/Modem Configuration command parameters defined in this 
specification.)  
8.8 Command Formats 
The following sections describe the formats of the chassis manager protocol payload 
commands. 
Note that the following sections copy command formats from the IPMI 2.0 
specification. In addition to IPMI-defined command formats, this section details 
system-defined OEM commands and modifications to IPMI command payloads, such 
as the Get Channel Authentication Capabilities command. 
8.8.1 Get Device ID 
Refer to the IPMI 2.0 specification. 
8.8.2 Get System GUID 
Refer to the IPMI 2.0 specification. 
 
 



Open Compute Project  Open CloudServer chassis management specification 
http://opencompute.org 49 
8.8.3 Get Channel Authentication Capabilities 
The blade should respond to the Get Channel Authentication Capabilities 
command outside of an active session. The command can also be executed within 
the context of an active session.    
Note: Byte 9 is a purposeful deviation from the IPMI 2.0 specification. 
Table 21 describes the Get Channel Authentication Capabilities command request. 
Table 21. Get Channel Authentication Capabilities Command Request 
Byte Description 
1 Channel number  
[7] – 1b = get IPMI v2.0+ extended data  
If the given channel supports authentication but does not support RMCP+ (for example, a 
serial channel), then the response data should return with bit [5] of byte 4 = 0b, and byte 
5 should return 01h  
0b = Backward compatible with IPMI v1.5  
Result response data only returns bytes 1:9, bit [7] of byte 3 (authentication type support) 
and bit [5] of byte 4 returns as 0b, bit [5] of byte byte 5 returns 00h.   
[6:4] – reserved  
[3:0] – channel number 
0h-7hBh, Fh = channel numbers  
Eh = retrieve information for channel this request was issued on. 
2 Requested maximum privilege level 
[7:4] – reserved 
[3:0] – requested privilege level 
0h = reserved 
1h = Callback level 
2h = User level 
3h = Operator level 
4h = Administrator level 
5h = OEM proprietary level 
 



 
50 January 28, 2014 
Table 22 describes the Get Channel Authentication Capabilities command response. 
Table 22. Get Channel Authentication Capabilities Command Response 
Byte Description 
1 Completion code 
2 Channel number 
Channel number that the authentication capabilities are being returned for.  
If the channel number in the request was set to Eh, this will return the channel number 
on which the request was received 
3 Authentication type support 
Returns the setting of the authentication type enable field from the configuration 
parameters for the given channel that corresponds to the requested maximum privilege 
level 
[7] -  1b = IPMI v2.0+ extended capabilities available (See extended capabilities field 
below) 
0b = IPMI v1.5 support only 
[6] -  reserved 
[5:0] -  IPMI v1.5 authentication type(s) enabled for given requested maximum privilege 
level 
All bits:  1b = supported 
0b = authentication type not available for use. 
[5] -  OEM proprietary (per OEM identified by the IANAOEM ID in the RMCPPing 
Response) 
[4] -  straight password / key 
[3] -  reserved 
[2] -  MD5 
[1] -  MD2 
[0] -  none 
4 [7:6] – reserved 
[5] - KG status (two-key login status). Applies to v2.0/RMCP+ RAKP authentication only 
(otherwise, ignore as “reserved”) 
0b = KG is set to default (all 0’s). User key KUID will be used in place of KG in RAKP 
(knowledge of KG not required for activating session) 
1b = KG is set to non -zero value (knowledge of both KG and user password (if not 
anonymous login) required for activating session) 



Open Compute Project  Open CloudServer chassis management specification 
http://opencompute.org 51 
Byte Description 
The following bits apply to IPMI v1.5 and v2.0: 
[4] -Per-message authentication status  
0b = Per-message authentication is enabled; packets to the BMC must be authenticated 
per authentication type used to activate the session and user level authentication setting 
1b = Per-message authentication is disabled; Authentication Type is “none” accepted for 
packets to the BMC after the session has been activated. 
[3] -  User Level Authentication status 
0b = User Level Authentication is enabled. User Level commands must  
be authenticated per Authentication Type used to activate the session. 
1b = User Level Authentication is disabled. Authentication Type “none” is accepted for 
User Level commands to the BMC. 
[2:0] -Anonymous Login status; this parameter returns values that tells the remote 
console whether there are users on the system that have “null” usernames. This can be 
used to guide the way the remote console presents login options to the user. (see IPMI 
v1.5 specification sections  6.9.1, “Anonymous Login” Convention and 6.9.2, Anonymous 
Login) 
[2] -  1b = Non-null usernames enabled. (One or more users are enabled that have non-
null usernames). 
[1] -  1b = Null usernames enabled (One or more users that have a null username, but 
non-null password, are presently enabled) 
[0] -  1b = Anonymous Login enabled (A user that has a null username and null password 
is presently enabled) 
5 For IPMI v1.5: -reserved 
For IPMI v2.0+: -extended capabilities 
[7:2] -  reserved 
[1] -    1b = channel supports IPMI v2.0 connections. 
[0] -    1b = channel supports IPMI v1.5 connections 
6:8 OEM ID Identification bytes:  
IANA Enterprise number for OEM/organization.  
This field must return an OEM Id irrespective of authentication type available.  
9 Compute blade = 0x04,  JBOD blade = 0x05 
 



 
52 January 28, 2014 
8.8.4 Get Session Challenge 
Refer to the IPMI 2.0 specification. 
8.8.5 Activate Session  
Refer to the IPMI 2.0 specification. 
8.8.6 Set Session Privilege Level 
Refer to the IPMI 2.0 specification. 
8.8.7 Close Session 
Refer to the IPMI 2.0 specification. 
8.8.8 Set Channel Access 
Refer to the IPMI 2.0 specification. 
8.8.9 Get Channel Access 
Refer to the IPMI 2.0 specification. 
8.8.10 Set User Access 
Refer to the IPMI 2.0 specification. 
 
8.8.11 Get User Access 
Refer to the IPMI 2.0 specification. 



Open Compute Project  Open CloudServer chassis management specification 
http://opencompute.org 53 
8.8.12 Set User Name 
Refer to the IPMI 2.0 specification. 
8.8.13 Get User Name 
Refer to the IPMI 2.0 specification. 
8.8.14 Set User Password 
Refer to the IPMI 2.0 specification. 
8.8.15 Get Chassis Status 
Refer to the IPMI 2.0 specification. 
8.8.16 Chassis Control 
Refer to the IPMI 2.0 specification. 
8.8.17 Chassis Identify 
Refer to the IPMI 2.0 specification. 
8.8.18 Set Power Restore Policy 
Refer to the IPMI 2.0 specification. 
8.8.19 Get System Restart Cause 
Refer to the IPMI 2.0 specification. 
8.8.20 Set System Boot Options 
Refer to the IPMI 2.0 specification. 



 
54 January 28, 2014 
8.8.21 Get System Boot Options 
Refer to the IPMI 2.0 specification. 
8.8.22 Get Sensor Reading Factors 
Refer to the IPMI 2.0 specification. 
8.8.23 Get Sensor Thresholds 
Refer to the IPMI 2.0 specification. 
8.8.24 Get Sensor Reading 
Refer to the IPMI 2.0 specification. 
8.8.25 Read FRU Data 
Refer to the IPMI 2.0 specification.  Offset should be in bytes no WORD.  Fru 
Inventory Area Info command is not required.. 
 
8.8.26 Write FRU Data 
Refer to the IPMI 2.0 specification.   Offset should be in bytes no WORD.  Fru 
Inventory Area Info command is not required.. 
8.8.27 Get SDR Repository 
Refer to the IPMI 2.0 specification. 
8.8.28 Reserve SDR Repository 
Refer to the IPMI 2.0 specification. 



Open Compute Project  Open CloudServer chassis management specification 
http://opencompute.org 55 
8.8.29 Get SDR 
Refer to the IPMI 2.0 specification.  
Note: Sensor types supported are Full (01h), Compact (02h), and Event Only (03h). 
8.8.30 Get SEL Info  
Refer to the IPMI 2.0 specification. 
8.8.31 Reserve SEL 
Refer to the IPMI 2.0 specification. 
The reservation process provides a limited amount of protection when records are 
being deleted or incrementally read.   
A Reservation ID value is returned in response to this command. This value is 
required in other requests, such as the Clear SEL command (commands will not 
execute unless the correct Reservation ID value is provided).  
As an example, if the chassis manager wants to clear the SEL, it first reserves the 
repository by issuing a Reserve SEL command. The application checks to see if all 
SEL entries have been handled before issuing the Clear SEL command. If a new event 
had been placed in the SEL after the records were checked but before the Clear SEL 
command, it is possible for the event to be lost. However, the addition of a new 
event to the SEL causes the present Reservation ID to be canceled, preventing the 
Clear SEL command from executing. The chassis manager can then repeat the 
reserve-check-clear process until it succeeds. 
8.8.32 Get SEL Entry 
Refer to the IPMI 2.0 specification. 
8.8.33 Add SEL Entry 
Refer to the IPMI 2.0 specification. 



 
56 January 28, 2014 
8.8.34 Clear SEL 
Refer to the IPMI 2.0 specification. 
8.8.35 Get SEL Time  
Refer to the IPMI 2.0 specification. 
Note: The time is an unsigned 32-bit value representing the local time as the 
number of seconds from 00:00:00, January 1, 1970 GMT. This format, which is based 
on a long-standing UNIX-based standard for time keeping, is sufficient to maintain 
time stamping with 1-second resolution past the year 2100. Similar time formats are 
used in ANSI C. 
8.8.36 Set SEL Time 
Refer to the IPMI 2.0 specification. 
8.8.37 Set Serial/Modem Configuration 
The Set Serial/Modem Configuration command is used for setting parameters such 
as the session inactivity timeout.  
Refer to the IPMI 2.0 specification. 
Note: The Set Serial/Modem Configuration parameters required are as follows:  
0. Set In Progress. 
2. Authentication type enables.  
If hard set privilege to Administrator with Authentication straight password / key.  
This parameter can be optional. 
4. Session Inactivity Timeout.   
Default should be 6 = 180 seconds.  
6. Session Termination.   
Default should be inactivity timeout enabled. 



Open Compute Project  Open CloudServer chassis management specification 
http://opencompute.org 57 
7. Used to set Baud-rate.   
Default should be 115.2K. 
8.8.38 Get Serial/Modem Configuration 
The Get Serial/Modem Configuration command is used for retrieving the 
configuration parameters from the Set Serial/Modem Configuration command. 
Refer to the IPMI 2.0 specification. 
8.8.39 Set Serial/Modem Mux 
The Set Serial/Modem Mux command switches control of the IPMI serial port to the 
system for console redirection. The command must response to the request message 
before transferring control of the serial port to the system for console redirection. 
Refer to the IPMI 2.0 specification. 
8.8.40 Serial/Modem Connection Active 
Refer to the IPMI 2.0 specification. 
8.8.41 Get Power Reading  
Refer to the DCMI 1.5 specification. 
8.8.42 Get Power Limit 
Refer to the DCMI 1.5 specification. 
8.8.43 Set Power Limit  
Refer to the DCMI 1.5 specification. 
8.8.44 Activate Power Limit  



 
58 January 28, 2014 
Refer to the DCMI 1.5 specification. 
8.8.45 Get Processor Info 
The Get Processor Info command returns the processor type and status.  
Table 23 describes the Get Processor Info request. 
Table 23. Get Processor Info Request 
Table 24 describes the Get Processor Info response. 
Table 24. Get Processor Info Response 
Bytes Description 
1 Completion code 
2 Processor type (see Table 60) 
3:4 Processor frequency (in MHz); LSB first 
5 Processor status: 
01h is present 
FFh is not present 
Table 25 lists the processor types. 
 
Table 25. Processor Types 
Byte Description 
1 Processor index (0-based index) 
Code Processor make and model Code Processor make and model 
00h Celeron (Intel)  0Eh  Lynnfield (Intel) 
01h Pentium III (Intel) 0Fh  Libson (AMB) 
02h Pentium 4 (Intel)  10h  Phenom II (AMD) 
03h Xeon (Intel)  11h  Athlon II (AMD) 



Open Compute Project  Open CloudServer chassis management specification 
http://opencompute.org 59 
8.8.46 Get Memory Info 
The Get Memory Info command returns information about a given memory DIMM. 
The command uses 1-based indexing.  
If zero is used as the DIMM index input parameter, the response message will follow 
Table 26. 
 
Table 26. Get Memory Info Response 
(if a zero index is provided in the request message as the DIMM index) 
Bytes Description 
1 Completion code 
2 DIMM slot number 
3 DIMM presence info in bit map for DIMM1 to DIMM8 
4 DIMM presence info in bit map for DIMM9 to DIMM16 
Table 27 describes the Get Memory Info request. 
Table 27. Get Memory Info Request 
04h Prestonia (Intel)  12h  Operation (AMB) 
05h Nocona (Intel)  13h SUZUKA (AMD) 
06h Opteron (AMB)  14h Core i3 (Intel) 
07h Dempsey (Intel)  15h Sandy Bridge (Intel) 
08h Clovertown (Intel)  16h Ivy Bridge (Intel) 
09h Tigerton (Intel)  17h Centerton (Intel) 
0Ah Dunnington (Intel)  FFh No CPU present 
0Bh Harpertown (Intel)   
Byte Description 
1 DIMM index (1-based index) 



 
60 January 28, 2014 
Table 28 describes the Get Memory Info response. 
Table 28. Get Memory Info Response (when 1+ index is provided as the DIMM index) 
Bytes Description 
1 Completion code 
2 Bit[7]: Is Low Voltage DIMM 
00h: Normal Voltage (1.5V) 
01h: Low Voltage (1.35V) 
Bit[6]: Actual DIMM running speed 
00h: Not  1333Mhz 
01h: 1333Mhz 
Bit[5]: Type 
00h: SDRAM 
01h: DDR-1 RAM 
02h: Rambus 
03h: DDR-2 RAM 
04h: FBDIMM 
05h: DDR-3 RAM 
FFh: No DIMM present 
3:4 DIMM speed (in MHz); LSB first 
5:6 DIMM size (in Megbytes); LSB first 
7 DIMM status: 
00h: Reserved 
01h: Unknown DIMM type 
02h: Ok 
03h: Not present 
05h: Single bit error 
07h: Multi bit error 
8.8.47 Get PCIe Info 



Open Compute Project  Open CloudServer chassis management specification 
http://opencompute.org 61 
The Get PCIe Info command returns the device type and status.  
Table 29 describes the Get PCIe Info request. 
Table 29. Get PCIe Info Request 
Table 30 describes the Get PCIe Info response. 
Table 30. Get PCIe Info Response 
Bytes Description 
1 Completion code 
2:3 Vendor ID; LSB 
4:5 Device ID; LSB 
6:7 System ID; LSB 
8:9 Sub-system ID; LSB 
8.8.48 Get NIC Info 
The Get NIC Info command returns the device type and status.  
Table 31 describes the Get NIC Info request. 
 
Table 31. Get NIC Info Request 
Table 32 describes the Get NIC Info response. 
Byte Description 
1 PCIe Slot Index (1-based index) 
1. PCIEX 16 
2. 10G Mezz 
3. SAS Mezz 
Byte Description 
1 NIC index (0-based index) 



 
62 January 28, 2014 
Table 32. Get NIC Info Response 
8.8.49 Get Disk Status 
The Get Disk Status command returns the status of each disk in the JBOD. Each disk 
will add 1 byte to the response (see byte 4+ in the response below). The byte that 
represents the disk will be split, with bits 7-6 representing the disk status and bits 5-
0 representing the unique disk number.  
The channel parameter in the request packet is used to select the target SAS 
controller/disk backplane for JBODs. The Get Disk Status command uses NetFn: 
2Eh/2Fh and command identifier C4h. 
Table 33 describes the Get Disk Status request. 
Table 33. Get Disk Status Request 
Table 34 describes the Get Disk Status response. 
Table 34. Get Disk Status Response 
Bytes Description 
1 Completion code  
2 Channel number 
Default for this specification is 0x00 
3 Disk count (total number of disks) 
4+N 7-6: disk status 
0=normal, 1=failed, 2=error 
5-0: disk number  
Bytes Description 
1 Completion code 
2:7 6-byte MAC address 
Byte Description 
1 [7:0] – reserve for channel number 0x00 



Open Compute Project  Open CloudServer chassis management specification 
http://opencompute.org 63 
Bytes Description 
Disk number/location ID 
8.8.50 Get Disk Info 
The Get Disk Info command returns sensor information regarding disks in the JBOD 
such as temperature.  
To conform with the communication protocol this command uses OEM reserved IPMI 
commands: 
 The Get Disk Status command uses NetFn: 2Eh/2Fh and command identifier 
C5h. 
 The Get Disk Temperature command is expected to return the status of each 
disk in the JBOD if disk temperatures are available. If not available, the 
command should report the JBOD temperature. The multiplier byte in the 
response message will be multiplied against the MS byte of the reading to 
assist in storing large and negative numbers. 
Table 35 describes the Get Disk Info request. 
Table 35. Get Disk Info Request 
Table 36 describes the Get Disk Info response. 
Table 36. Get Disk Info Response 
Bytes Description 
1 IPMI completion code  
2 Reading unit (see IPMI table for Table 15. Required IPMI Commands for BladesTable 
15: sensor unit type codes) 
3 MS byte multiplier (byte 4); byte should represent unsigned int 
Byte Description 
1 Channel number 
00h for single channel 
2 Disk number (if per-disk temperatures are available, otherwise 00h got JBOD) 



 
64 January 28, 2014 
Bytes Description 
[7] 1b = negative multiplier 
0b = positive multiplier 
[6-0] reading MS byte multiplier 
4 Reading LS byte first 
5 Reading MS byte 
Following are examples of disk packets: 
Request Packet: 
0xA0202EB28104C50000B6A5 
Example Response Packet for 32.00 degrees C: 
A0812F502004C50001000020F6A5 
Example Response Packet for -5.02 degrees C: 
A0812F502004C500018102058EA5  
9 Chassis Manager REST API 
The sections that follow describe the chassis manager Rest API. 
9.1 User Roles and API Access 
The chassis manager web service provides a full set of security features, including 
encryption, integrity, authentication, and fine-grained API-level authorization. 
9.2 Encryption and Service Credentials 
All data communication between the chassis manager web service and clients (web 
browser or command-line interface) is encrypted using secure socket layers (SSL).  
The system uses signature-based checksum (signed packets) to prevent tampering 
and sends data secure HTTP (HTTPS) to ensure integrity. The chassis manager web 
service is also authenticated against the client using Microsoft Certificate Services. 



Open Compute Project  Open CloudServer chassis management specification 
http://opencompute.org 65 
9.3 Client Credentials/Authentication 
Client authentication is based on either machine-local or domain-user Windows 
credentials. Client Windows credentials are automatically obtained from the client 
computer based on the context of the logged-in user. 
9.4 Role-Based API-Level Authorization 
Client authorization to the chassis manager web service is provided at the granularity 
of the service APIs. The chassis manager APIs are categorized into three security 
domains:  
 U1─APIs that perform chassis manager management functions and manage 
devices that are connected to the chassis manager (for example, blades and 
power supply units).  
 U2─APIs that manage devices (for example, blades and power supply units) that 
are connected to the chassis manager. 
 U3─APIs that perform only read-only operations. 
Note: U1 includes all chassis manager APIs, while U2 and U3 include only a subset of 
the chassis manager APIs. Note also that U3 is a subset of U2, which is a subset of 
U1. 
Users authorized to perform chassis manager functions can be categorized into three 
Windows security domains or groups: 
 AcsCmAdmin─Users in this group are authorized to perform functions in U1. 
They have access to all APIs, including APIs for chassis manager management 
functions like “add-user” and “set-NIC.” 
 AcsCmOperator─Users in this group are authorized to perform functions in U2, 
and have access to all APIs except those for chassis manager management 
functions. 
 AcsCmUser─Users in this group are authorized to perform functions in U3, and 
can only access read-only APIs. 



 
66 January 28, 2014 
Any user attempting to access the chassis manager APIs will be authorized based on 
their role or group. Users who do not belong to any of the three authorization roles 
or groups are denied access to chassis manager API functionalities. 
The three Windows groups are available in each chassis manager, and local chassis 
manager users can be assigned to any of the three local roles (CM-1/AcsCmAdmin, 
CM-1/AcsCmOperator, and CM-1/AcsCmUser) using the “add user” and “change 
user” APIs.  
The three authorization roles can also be created in each domain that wants to 
communicate with the chassis manager. For example, Domain-1/User-1 will be 
checked against the corresponding domain’s authorization roles (Domain-
1/AcsCmAdmin, Domain-1/AcsCmOperator, or Domain-1/AcsCmUser). By default, a 
chassis manager administrator has privileges that are equal to the authorization role 
AcsCmAdmin. 
Table 37 lists the APIs and the corresponding authorized user roles. 
Table 37. Chassis Manager APIs and Corresponding Authorized Roles 
APIs AcsCmAdmin AcsCmOperator AcsCmUser 
Health/status information APIs 
GetChassisInfo X X X 
GetBladeInfo X X X 
GetAllBladesInfo X X X 
Blade management APIs 
GetBladeHealth X X X 
SetBladeAttentionLEDOn X X  
SetAllBladesAttentionLEDOn X X  
SetBladeAttentionLEDOff X X  
SetAllBladesAttentionLEDOff X X  
SetBladeDefaultPowerStateOn X X  
SetAllBladesDefaultPowerStateOn X X  



Open Compute Project  Open CloudServer chassis management specification 
http://opencompute.org 67 
APIs AcsCmAdmin AcsCmOperator AcsCmUser 
SetBladeDefaultPowerStateOff X X  
SetAllBladesDefaultPowerStateOff X X  
GetBladeDefaultPowerState X X X 
GetAllBladesDefaultPowerState X X X 
GetPowerState X X X 
GetAllPowerState X X X 
SetPowerOn X X  
SetAllPowerOn X X  
SetPowerOff X X  
SetAllPowerOff X X  
GetBladeState X X X 
GetAllBladesState X X X 
SetBladeOn X X  
SetAllBladesOn X X  
SetBladeOff X X  
SetAllBladesOff X X  
SetBladeActivePowerCycle X X  
SetAllBladesActivePowerCycle X X  
ReadBladeLog X X X 
ReadBladeLogWithTimeStamp X X X 
ClearBladelog X X  
GetBladePowerReading X X X 
GetAllBladesPowerReading X X X 
GetBladePowerLimit X X X 
GetAllBladesPowerLimit X X X 



 
68 January 28, 2014 
APIs AcsCmAdmin AcsCmOperator AcsCmUser 
SetBladePowerLimit X X  
SetAllBladesPowerLimit X X  
SetBladePowerLimitOn X X  
SetAllBladesPowerLimitOn X X  
SetBladePowerLimitOff X X  
SetAllBladesPowerLimitOff X X  
GetNextBoot X X X 
SetNextBoot X X  
StartBladeSerialSession X   
SendBladeSerialData X   
ReceiveBladeSerialData X   
StopBladeSerialSession X   
Serial console device APIs 
StartSerialPortConsole X X  
StopSerialPortConsole X X  
SendSerialPortData X X  
ReceiveSerialPortData X X  
Chassis management APIs 
SetChassisAttentionLEDOn X X  
SetChassisAttentionLEDOff X X  
GetChassisAttentionLEDStatus X X X 
ReadChassisLog X X X 
ClearChassisLog X X  
ReadChassisLogWithTimeStamp X X X 



Open Compute Project  Open CloudServer chassis management specification 
http://opencompute.org 69 
APIs AcsCmAdmin AcsCmOperator AcsCmUser 
GetChassisHealth X X X 
SetACSocketPowerStateOn X X  
SetACSocketPowerStateOff X X  
GetACSocketPowerState X X X 
GetChassisNetworkProperties X  X 
AddChassisControllerUser X   
ChangeChassisControllerUserPassword X   
ChangeChassisControllerUserRole X   
RemoveChassisControllerUser X   
9.5 REST API: Response and Completion Codes 
The chassis manager interface is based on REST to more easily interface with the 
machines. The sections that follow describe the chassis manager functionality and 
provide the corresponding APIs and descriptions. 
Each REST API call has the following information encapsulated in its return packet to 
provide high-level response status information: 
 <byte>  
completion code  
 <string>  
status description (a textual description of the result) when completion code is 
anything other than success. 
 <int>  
API version 
Version number of the REST API. Currently, this has value ‘1’; it will be updated 
upon future API or response packet structure changes. 
Note: The NoActiveSerialSession = 0xB2 // error is thrown for Stop/Send/Receive 
serial session commands for both the blade and the port console when there is no 
active serial session. If you see this error, use a startserialsession API to create an 
active session. 



 
70 January 28, 2014 
9.6 REST API: Descriptions, Usage Scenarios, and Sample Responses 
The sections that follow provide information about the chassis manager REST APIs. 
 
9.6.1 Gets Information about Chassis 
ChassisInfoResponse GetChassisInfo(bool bladeInfo, bool psuInfo, bool chassisInfo) 
https://localhost:8000/GetChassisInfo?bladeinfo=true&psuInfo=true&chassisInfo=true  
Usage scenario:  
This API is used to get the status of chassis components including blades (for example, GUID 
and power status), power supplies (for example, power draw, status, and serial number), and 
chassis manager (for example, MAC/IP address of the network interfaces, and version 
information). 
Input parameters: (If no parameters are specified, the command fetches result for all) 
 bladeInfo (shows information about blades, optional) 
 psuInfo (shows information about power supplies, optional) 
 chassisInfo (show chassis manager information, optional) 
Sample response: 
<ChassisInfoResponse 
xmlns="http://schemas.datacontract.org/2004/07/Microsoft.GFS.ACS.Contracts" 
xmlns:i="http://www.w3.org/2001/XMLSchema-instance"> 
  <CompletionCode>Success</CompletionCode>  
  <statusDescription></statusDescription> 
  <apiVersion>1</apiVersion> 
<bladeCollections> 
<BladeInfo> 
  <CompletionCode>Success</CompletionCode> 
  <statusDescription></statusDescription>  
  <apiVersion>1</apiVersion> 
  <bladeGuid>ffffffff-ffff-ffff-ffff-ffffffffffff</bladeGuid>  
  <bladeName>BLADE1</bladeName>  
  <bladeMacAddress>Not Applicable</bladeMacAddress>  
  <id>1</id>  
  <powerState>ON</powerState>  
  </BladeInfo> 
<BladeInfo> 



Open Compute Project  Open CloudServer chassis management specification 
http://opencompute.org 71 
  <CompletionCode>Success</CompletionCode>  
  <statusDescription></statusDescription> 
  <apiVersion>1</apiVersion> 
  <bladeGuid>ffffffff-ffff-ffff-ffff-ffffffffffff</bladeGuid>  
  <bladeName>BLADE2</bladeName>  
  <bladeMacAddress>Not Applicable</bladeMacAddress>  
  <id>2</id>  
  <powerState>ON</powerState>  
  </BladeInfo> 
... 
<BladeInfo> 
  <CompletionCode>Success</CompletionCode>  
  <statusDescription></statusDescription> 
  <apiVersion>1</apiVersion> 
  <bladeGuid>ffffffff-ffff-ffff-ffff-ffffffffffff</bladeGuid>  
  <bladeName>BLADE24</bladeName>  
  <bladeMacAddress>Not Applicable</bladeMacAddress>  
  <id>24</id>  
  <powerState>ON</powerState>  
  </BladeInfo> 
  </bladeCollections> 
 
<chassisController> 
  <CompletionCode>Success</CompletionCode> 
  <statusDescription></statusDescription>  
  <apiVersion>1</apiVersion> 
  <assetTag />  
  <firmwareVersion />  
  <hardwareVersion>0</hardwareVersion>  
- <networkProperties> 
- <ChassisNetworkPropertiesResponse> 
  <completionCode>Success</completionCode> 
  <statusDescription></statusDescription>  
  <apiVersion>1</apiVersion> 
  <ipAddress i:nil="true" />  
  <macAddress>08:9E:01:18:0C:07</macAddress>  
  <dhcpEnabled>false</dhcpEnabled>  



 
72 January 28, 2014 
  <dhcpServer i:nil="true" />  
  <dnsAddress i:nil="true" />  
  <dnsDomain i:nil="true" />  
  <dnsHostName i:nil="true" />  
  <gatewayAddress i:nil="true" />  
  <subnetMask i:nil="true" />  
  </ChassisNetworkPropertiesResponse> 
- <ChassisNetworkPropertiesResponse> 
  <completionCode>Success</completionCode>  
  <statusDescription></statusDescription> 
  <apiVersion>1</apiVersion> 
  <ipAddress>xxx.xxx.xxx.xx</ipAddress>  
  <macAddress>xx:xx:xx:xx:xx:xx</macAddress>  
  <dhcpEnabled>true</dhcpEnabled>  
  <dhcpServer>xxx.xxx.xxx.x</dhcpServer>  
  <dnsAddress i:nil="true" />  
  <dnsDomain>xxx.lab</dnsDomain>  
  <dnsHostName>MACHINE2</dnsHostName>  
  <gatewayAddress i:nil="true" />  
  <subnetMask>xxx.xxx.xxx.x</subnetMask>  
  </ChassisNetworkPropertiesResponse> 
  </networkProperties> 
  <serialNumber />  
  <systemUptime>00:00:41.4301650</systemUptime>  
  </chassisController> 
 
<psuCollections> 
<PsuInfo> 
  <CompletionCode>Success</CompletionCode> 
  <statusDescription></statusDescription>  
  <apiVersion>1</apiVersion> 
  <id>1</id>  
  <powerOut>1011</powerOut>  
  <serialNumber>46-49-51-44-31-32-32-32-30-30-30-31-33-32</serialNumber>  
  <state>ON</state>  
  </PsuInfo> 



Open Compute Project  Open CloudServer chassis management specification 
http://opencompute.org 73 
<PsuInfo> 
  <CompletionCode>Success</CompletionCode>  
  <statusDescription></statusDescription> 
  <apiVersion>1</apiVersion> 
  <id>2</id>  
  <powerOut>960</powerOut>  
  <serialNumber>46-49-51-44-31-32-32-32-30-30-30-31-30-35</serialNumber>  
  <state>ON</state>  
  </PsuInfo> 
... 
<PsuInfo> 
  <CompletionCode>Success</CompletionCode>  
  <statusDescription></statusDescription> 
  <apiVersion>1</apiVersion> 
  <id>6</id>  
  <powerOut>925</powerOut>  
  <serialNumber>46-49-51-44-31-32-32-32-30-30-30-31-30-37</serialNumber>  
  <state>ON</state>  
  </PsuInfo> 
  </psuCollections> 
  </ChassisInfoResponse> 
9.6.2 Gets Information about Blade 
BladeInfoResponse  GetBladeInfo(int bladeId) 
https://localhost:8000/GetBladeInfo?bladeid=1 
Usage scenario:  
This API is used to get information about the blade (for example serial number and version 
information).   
Input parameters: 
 bladeId (blade index 1-48) 
Sample response:  
<BladeInfoResponse 
xmlns="http://schemas.datacontract.org/2004/07/Microsoft.GFS.ACS.Contracts" 
xmlns:i="http://www.w3.org/2001/XMLSchema-instance"> 
 <bladeResponse> 
  <CompletionCode>Success</CompletionCode>  



 
74 January 28, 2014 
  <statusDescription></statusDescription> 
  <apiVersion>1</apiVersion> 
  <bladeNumber>1</bladeNumber>  
  </bladeResponse> 
 <detailedBladeInfo> 
  <alertEnabled>true</alertEnabled>  
  <assetTag> Will be added </assetTag>  
 <bladeBmc> 
  <gateway>Not applicable</gateway>  
  <guid>4647ff2b-cb75-4ad6-85de-c612c5abdf87</guid>  
  <ipAddress>Not applicable</ipAddress>  
  <ipmiVersion>Not applicable</ipmiVersion>  
  <macAddress>Not applicable</macAddress>  
  <netmask>Not applicable</netmask>  
  <solEnabled>true</solEnabled>  
  <vlanTag>1</vlanTag>  
  </bladeBmc> 
  <dhcp>false</dhcp>  
  <firmwareVersion>01.03</firmwareVersion>  
  <hardwareVersion>V1.0</hardwareVersion>  
  <id>1</id>  
  <ipAddress>0.0.0.0</ipAddress>  
  <ipmiEnabled>true</ipmiEnabled>  
  <logEnabled>true</logEnabled>  
  <macAddress>00-00-00-00-00-00</macAddress>  
  <numberComputeNodes>1</numberComputeNodes>  
  <serialNumber>MH822400349</serialNumber>  
  </detailedBladeInfo> 
  </BladeInfoResponse> 
9.6.3 Gets Information about All Blades 
GetAllBladesInfoResponse  GetAllBladesInfo() 
https://localhost:8000/GetAllBladesInfo? 
Usage scenario: 



Open Compute Project  Open CloudServer chassis management specification 
http://opencompute.org 75 
This API is used to get information about all blades (for example serial numbers and version 
information). 
Input parameters: 
 bladeId  (blade index 1-48) 
Sample response:  
<GetAllBladesInfoResponse 
xmlns="http://schemas.datacontract.org/2004/07/Microsoft.GFS.ACS.Contracts" 
xmlns:i="http://www.w3.org/2001/XMLSchema-instance"> 
 <BladeInfoResponse> 
 <bladeResponse> 
  <CompletionCode>Success</CompletionCode>  
  <statusDescription></statusDescription> 
  <apiVersion>1</apiVersion> 
  <bladeNumber>1</bladeNumber>  
  </bladeResponse> 
 <detailedBladeInfo> 
  <alertEnabled>true</alertEnabled>  
  <assetTag>Will be added</assetTag>  
 <bladeBmc> 
  <gateway>Not applicable</gateway>  
  <guid>b560b268-c9e0-46da-8029-5f8d2eeed61e</guid>  
  <ipAddress>Not applicable</ipAddress>  
  <ipmiVersion>Not applicable</ipmiVersion>  
  <macAddress>Not applicable</macAddress>  
  <netmask>Not applicable</netmask>  
  <solEnabled>true</solEnabled>  
  <vlanTag>1</vlanTag>  
  </bladeBmc> 
  <dhcp>false</dhcp>  
  <firmwareVersion>01.03</firmwareVersion>  
  <hardwareVersion>V1.0</hardwareVersion>  
  <id>1</id>  
  <ipAddress>0.0.0.0</ipAddress>  
  <ipmiEnabled>true</ipmiEnabled>  
  <logEnabled>true</logEnabled>  
  <macAddress>00-00-00-00-00-00</macAddress>  
  <numberComputeNodes>1</numberComputeNodes>  



 
76 January 28, 2014 
  <serialNumber>MH822400349</serialNumber>  
  </detailedBladeInfo> 
  </BladeInfoResponse> 
... 
 <BladeInfoResponse> 
 <bladeResponse> 
  <CompletionCode>Success</CompletionCode>  
  <statusDescription></statusDescription> 
  <apiVersion>1</apiVersion> 
  <bladeNumber>24</bladeNumber>  
  </bladeResponse> 
 <detailedBladeInfo> 
  <alertEnabled>true</alertEnabled>  
  <assetTag>Blank For Now, need to locate in FRU</assetTag>  
 <bladeBmc> 
  <gateway>Not applicable</gateway>  
  <guid>c7954895-cb36-4a79-a5b3-8fa2fbb0795a</guid>  
  <ipAddress>Not applicable</ipAddress>  
  <ipmiVersion>Not applicable</ipmiVersion>  
  <macAddress>Not applicable</macAddress>  
  <netmask>Not applicable</netmask>  
  <solEnabled>true</solEnabled>  
  <vlanTag>1</vlanTag>  
  </bladeBmc> 
  <dhcp>false</dhcp>  
  <firmwareVersion>01.03</firmwareVersion>  
  <hardwareVersion>V1.0</hardwareVersion>  
  <id>24</id>  
  <ipAddress>0.0.0.0</ipAddress>  
  <ipmiEnabled>true</ipmiEnabled>  
  <logEnabled>true</logEnabled>  
  <macAddress>00-00-00-00-00-00</macAddress>  
  <numberComputeNodes>1</numberComputeNodes>  
  <serialNumber>MH822400334</serialNumber>  
  </detailedBladeInfo> 
  </BladeInfoResponse> 



Open Compute Project  Open CloudServer chassis management specification 
http://opencompute.org 77 
  </GetAllBladesInfoResponse> 
9.6.4 Turns Chassis Attention LED ON 
ChassisResponse   SetChassisAttentionLEDOn() 
https://localhost:8000/SetChassisAttentionLEDOn? 
Usage scenario:  
This API is used to turn the chassis attention LED ON. 
The attention LED indicates that the chassis manager needs attention. It directs service 
technicians to the correct chassis for repair. chassis manager logs are available through the 
management system to direct repair (through the ReadChassisLog() API). Users can also flag a 
service requirement by turning ON the attention LED. When possible, repairs will also be self-
directed by the chassis management system. Operators/users must make sure that the chassis 
attention LED is turned OFF after service is complete. 
Input parameters: 
 None 
Sample response: 
<ChassisResponse 
xmlns="http://schemas.datacontract.org/2004/07/Microsoft.GFS.ACS.Contracts" 
xmlns:i="http://www.w3.org/2001/XMLSchema-instance"> 
  <completionCode>Success</completionCode>  
  <statusDescription></statusDescription> 
  <apiVersion>1</apiVersion> 
  </ChassisResponse> 
9.6.5 Turns Chassis Attention LED OFF 
ChassisResponse SetChassisAttentionLEDOff() 
https://localhost:8000/SetChassisAttentionLEDOff? 
Usage scenario:  
This API is used to turn the chassis attention LED OFF. 
The attention LED indicates that the chassis manager needs attention. It directs service 
technicians to the correct chassis for repair. chassis manager logs are available through the 
management system to direct repair (through the ReadChassisLog() API). Users can also flag a 
service requirement by turning ON the attention LED. When possible, repairs will also be self-
directed by the chassis management system. Operators/users must make sure that the chassis 
attention LED is turned OFF after service is complete. 



 
78 January 28, 2014 
Input parameters: 
 None 
Sample response: 
<ChassisResponse 
xmlns="http://schemas.datacontract.org/2004/07/Microsoft.GFS.ACS.Contracts" 
xmlns:i="http://www.w3.org/2001/XMLSchema-instance"> 
  <completionCode>Success</completionCode>  
  <statusDescription></statusDescription> 
  <apiVersion>1</apiVersion> 
  </ChassisResponse> 
9.6.6 Gets Chassis Attention LED Status 
LEDStatusResponse  GetChassisAttentionLEDStatus() 
https://localhost:8000/GetChassisAttentionLEDStatus? 
Usage scenario:  
This API gets the chassis attention LED status (whether ON or OFF). 
The attention LED indicates that the chassis manager needs attention. It directs service 
technicians to the correct chassis for repair. chassis manager logs are available through the 
management system to direct repair (through the ReadChassisLog() API). Users can also flag a 
service requirement by turning ON the attention LED. When possible, repairs will also be self-
directed by the chassis management system. Operators/users must make sure that the chassis 
attention LED is turned OFF after service is complete. 
Input parameters: 
 None 
Sample response: 
<LEDStatusResponse 
xmlns="http://schemas.datacontract.org/2004/07/Microsoft.GFS.ACS.Contracts" 
xmlns:i="http://www.w3.org/2001/XMLSchema-instance"> 
  <completionCode>Success</completionCode>  
  <statusDescription></statusDescription> 
  <apiVersion>1</apiVersion> 
  <ledState>OFF</ledState>  
  </LEDStatusResponse> 
 



Open Compute Project  Open CloudServer chassis management specification 
http://opencompute.org 79 
9.6.7 Turns Blade Attention LED ON 
BladeResponse SetBladeAttentionLEDOn(int bladeId) 
https://localhost:8000/SetBladeAttentionLEDOn?bladeId=1 
Usage scenario:  
This API turns the blade attention LED ON. 
The attention LED indicates that the blade needs attention. It directs service technicians to the 
correct blade for repair. Blade logs are available through the management system to direct 
repair (through the ReadBladeLog() API). Users can also flag a service requirement by turning 
ON the attention LED. Operators/users must make sure that the blade attention LED is turned 
OFF after service is complete. 
Input parameters: 
 bladeId (blade index 1-48) 
Sample response: 
<BladeResponse 
xmlns="http://schemas.datacontract.org/2004/07/Microsoft.GFS.ACS.Contracts" 
xmlns:i="http://www.w3.org/2001/XMLSchema-instance"> 
  <CompletionCode>Success</CompletionCode>  
  <statusDescription></statusDescription> 
  <apiVersion>1</apiVersion> 
  <bladeNumber>1</bladeNumber>  
  </BladeResponse> 
 
9.6.8 Turns All Blade Attention LEDs ON 
AllBladesResponse SetAllBladesAttentionLEDOn() 
https://localhost:8000/SetAllBladesAttentionLEDOn? 
Usage scenario:  
This API turns the attention LEDs on all blades ON. 
The attention LED indicates that the blade needs attention. It directs service technicians to the 
correct blade for repair. Blade logs are available through the management system to direct 
repair (through the ReadBladeLog() API). Users can also flag a service requirement by turning 
ON the attention LED. Operators/users must make sure that the blade attention LED is turned 
OFF after service is complete. 



 
80 January 28, 2014 
Note that when multiple users are actively trying to access/modify the same state of a single 
blade or of different blades, ordering is not guaranteed. 
Input parameters: 
 None 
Sample response: 
- <AllBladesResponse 
xmlns="http://schemas.datacontract.org/2004/07/Microsoft.GFS.ACS.Contracts" 
xmlns:i="http://www.w3.org/2001/XMLSchema-instance"> 
- <BladeResponse> 
  <CompletionCode>Success</CompletionCode>  
  <statusDescription></statusDescription> 
  <apiVersion>1</apiVersion> 
  <bladeNumber>1</bladeNumber>  
  </BladeResponse> 
- <BladeResponse> 
  <CompletionCode>Success</CompletionCode>  
  <statusDescription></statusDescription> 
  <apiVersion>1</apiVersion> 
  <bladeNumber>2</bladeNumber>  
  </BladeResponse> 
… 
- <BladeResponse> 
  <CompletionCode>Success</CompletionCode>  
  <statusDescription></statusDescription> 
  <apiVersion>1</apiVersion> 
  <bladeNumber>24</bladeNumber>  
  </BladeResponse> 
  </AllBladesResponse> 
9.6.9 Turns Blade Attention LED OFF 
BladeResponse SetBladeAttentionLEDOff(int bladeId) 
https://localhost:8000/SetBladeAttentionLEDOff?bladeId=1 
Usage scenario:  



Open Compute Project  Open CloudServer chassis management specification 
http://opencompute.org 81 
This API turns the blade attention LED OFF. 
The attention LED indicates that the blade needs attention. It directs service technicians to the 
correct blade for repair. Blade logs are available through the management system to direct 
repair (through the ReadBladeLog() API). Users can also flag a service requirement by turning 
ON the attention LED. Operators/users must make sure that the blade attention LED is turned 
OFF after service is complete. 
Input parameters: 
 bladeId (blade index 1-48) 
Sample response: 
<BladeResponse 
xmlns="http://schemas.datacontract.org/2004/07/Microsoft.GFS.ACS.Contracts" 
xmlns:i="http://www.w3.org/2001/XMLSchema-instance"> 
  <CompletionCode>Success</CompletionCode>  
  <statusDescription></statusDescription> 
  <apiVersion>1</apiVersion> 
  <bladeNumber>1</bladeNumber>  
  </BladeResponse> 
9.6.10 Turns All Blade Attention LEDs OFF 
AllBladesResponse SetAllBladesAttentionLEDOff() 
https://localhost:8000/SetAllBladesAttentionLEDOff? 
Usage scenario:  
This API is used to turn the attention LED on all blades OFF. 
The attention LED indicates that the blade needs attention. It directs service technicians to the 
correct blade for repair. Blade logs are available through the management system to direct 
repair (through the ReadBladeLog() API). Users can also flag a service requirement by turning 
ON the attention LED. Operators/users must make sure that the blade attention LED is turned 
OFF after service is complete. 
Note that when multiple users are actively trying to access/modify the same state of a single 
blade or of different blades, ordering is not guaranteed. 
Input parameters: 
 None 
Sample response: 
- <AllBladesResponse 
xmlns="http://schemas.datacontract.org/2004/07/Microsoft.GFS.ACS.Contracts" 
xmlns:i="http://www.w3.org/2001/XMLSchema-instance"> 



 
82 January 28, 2014 
- <BladeResponse> 
  <CompletionCode>Success</CompletionCode>  
  <statusDescription></statusDescription> 
  <apiVersion>1</apiVersion> 
  <bladeNumber>1</bladeNumber>  
  </BladeResponse> 
- <BladeResponse> 
  <CompletionCode>Success</CompletionCode> 
  <statusDescription></statusDescription>  
  <apiVersion>1</apiVersion> 
  <bladeNumber>2</bladeNumber>  
  </BladeResponse> 
… 
- <BladeResponse> 
  <CompletionCode>Success</CompletionCode>  
  <statusDescription></statusDescription> 
  <apiVersion>1</apiVersion> 
  <bladeNumber>24</bladeNumber>  
  </BladeResponse> 
  </AllBladesResponse> 
9.6.11 Sets Default Blade Power State ON 
BladeResponse SetBladeDefaultPowerStateOn(int bladeId) 
https://localhost:8000/SetBladeDefaultPowerStateOn?bladeId=1 
Usage scenario:  
This API sets the default power state of a blade ON. 
The default power state of the blade is the state of the blade after it receives AC power, 
either when a blade is initially inserted in the slot or when power returns after a utility failure. 
If the default state is set to OFF, the blade will not be powered ON after receiving AC input 
power, and an explicit SetBladeActivePowerOn() API will need to be sent to power ON the 
blade. Note that the blade default power state does not affect the active power state of the 
blade, only their behavior after a power recycle. 



Open Compute Project  Open CloudServer chassis management specification 
http://opencompute.org 83 
Input parameters: 
 bladeId (blade index 1-48) 
Sample response: 
<BladeResponse 
xmlns="http://schemas.datacontract.org/2004/07/Microsoft.GFS.ACS.Contracts" 
xmlns:i="http://www.w3.org/2001/XMLSchema-instance"> 
  <CompletionCode>Success</CompletionCode>  
  <statusDescription></statusDescription> 
  <apiVersion>1</apiVersion> 
  <bladeNumber>1</bladeNumber>  
  </BladeResponse> 
9.6.12 Sets Default Power State of All Blades ON 
AllBladesResponse SetAllBladesDefaultPowerStateOn() 
https://localhost:8000/SetAllBladesDefaultPowerStateOn? 
Usage scenario:  
This API sets the default power state of all blades ON. 
The default power state of the blade is the state of the blade after it receives AC power, 
either when a blade is initially inserted in the slot or when power returns after a utility failure. 
If the default state is set to OFF, the blade will not be powered ON after receiving AC input 
power, and an explicit SetBladeActivePowerOn() API will need to be sent to power ON the 
blade. Note that the blade default power state does not affect the active power state of the 
blade; the default power state only affects their behavior after a power recycle. 
Note that when multiple users are actively trying to access/modify the same state of a single 
blade or of different blades, ordering is not guaranteed. 
Input parameters: 
 None 
Sample response: 
- <AllBladesResponse 
xmlns="http://schemas.datacontract.org/2004/07/Microsoft.GFS.ACS.Contracts" 
xmlns:i="http://www.w3.org/2001/XMLSchema-instance"> 
- <BladeResponse> 
  <CompletionCode>Success</CompletionCode>  
  <statusDescription></statusDescription> 
  <apiVersion>1</apiVersion> 



 
84 January 28, 2014 
  <bladeNumber>1</bladeNumber>  
  </BladeResponse> 
- <BladeResponse> 
  <CompletionCode>Success</CompletionCode> 
  <statusDescription></statusDescription>  
  <apiVersion>1</apiVersion> 
  <bladeNumber>2</bladeNumber>  
  </BladeResponse> 
... 
- <BladeResponse> 
  <CompletionCode>Success</CompletionCode>  
  <statusDescription></statusDescription> 
  <apiVersion>1</apiVersion> 
  <bladeNumber>24</bladeNumber>  
  </BladeResponse> 
  </AllBladesResponse> 
9.6.13 Sets Default Blade Power State OFF 
BladeResponse SetBladeDefaultPowerStateOff(int bladeId) 
http://localhost:8000/SetBladeDefaultPowerStateOff?bladeId=1 
Usage scenario:  
This API sets the default power state of a blade OFF. 
The default power state of the blade is the state of the blade after it receives AC power, 
either when a blade is initially inserted in the slot or when power returns after a utility failure. 
If the default state is set to OFF, the blade will not be powered ON after receiving AC input 
power, and an explicit SetBladeActivePowerOn() API will need to be sent to power ON the 
blade. Note that the blade default power state does not affect the active power state of the 
blade; the default power state of a blade only affects the behavior after a power recycle. 
Input parameters: 
 bladeId (blade index 1-48) 
Sample response: 
<BladeResponse 
xmlns="http://schemas.datacontract.org/2004/07/Microsoft.GFS.ACS.Contracts" 



Open Compute Project  Open CloudServer chassis management specification 
http://opencompute.org 85 
xmlns:i="http://www.w3.org/2001/XMLSchema-instance"> 
  <completionCode>Success</completionCode>  
  <statusDescription></statusDescription> 
  <apiVersion>1</apiVersion> 
  <bladeNumber>1</bladeNumber>  
  </BladeResponse> 
9.6.14 Sets Default Power State of All Blades OFF 
AllBladesResponse SetAllBladesDefaultPowerStateOff() 
http://localhost:8000/SetAllBladesDefaultPowerStateOff?bladeId=1 
Sets the default power state of all blades OFF 
Usage scenario:  
This API sets the default power state of all blades OFF. 
The default power state of the blade is the state of the blade after it receives AC power, 
either when a blade is initially inserted in the slot or when power returns after a utility failure. 
If the default state is set to OFF, the blade will not be powered ON after receiving AC input 
power, and an explicit SetBladeActivePowerOn() API will need to be sent to power ON the 
blade. Note that the blade default power state does not affect the active power state of the 
blade; the default power state only affects the behavior after a power recycle. 
Note also that when multiple users are actively trying to access/modify the same state of a 
single blade or of different blades, ordering is not guaranteed. 
Input parameters: 
 None 
Sample response: 
- <AllBladesResponse 
xmlns="http://schemas.datacontract.org/2004/07/Microsoft.GFS.ACS.Contracts" 
xmlns:i="http://www.w3.org/2001/XMLSchema-instance"> 
- <BladeResponse> 
  <completionCode>Success</completionCode>  
  <statusDescription></statusDescription> 
  <apiVersion>1</apiVersion> 
  <bladeNumber>1</bladeNumber>  
  </BladeResponse> 
- <BladeResponse> 
  <completionCode>Success</completionCode>  



 
86 January 28, 2014 
  <statusDescription></statusDescription> 
  <apiVersion>1</apiVersion> 
  <bladeNumber>2</bladeNumber>  
  </BladeResponse> 
... 
- <BladeResponse> 
  <completionCode>Success</completionCode>  
  <statusDescription></statusDescription> 
  <apiVersion>1</apiVersion> 
  <bladeNumber>24</bladeNumber>  
  </BladeResponse> 
  </AllBladesResponse> 
9.6.15 Gets Default Blade Power State  
BladeStateResponse GetBladeDefaultPowerState(int bladeId) 
https://localhost:8000/GetBladeDefaultPowerState?bladeId=1 
Usage scenario:  
This API gets the default power state of the blade.  
The default power state of the blade is the state of the blade after it receives AC power, 
either when a blade is initially inserted in the slot or when power returns after a utility failure. 
If the default state is set to OFF, the blade will not be powered ON after receiving AC input 
power, and an explicit SetBladeActivePowerOn() API will need to be sent to power ON the 
blade. Note that the blade default power state does not affect the active power state of the 
blade; the default power state only affects the behavior after a power recycle. 
Input parameters: 
 bladeId (blade index 1-48) 
Sample response: 
BladeStateResponse 
xmlns="http://schemas.datacontract.org/2004/07/Microsoft.GFS.ACS.Contracts" 
xmlns:i="http://www.w3.org/2001/XMLSchema-instance"> 
- <bladeResponse> 
  <completionCode>Success</completionCode>  
  <statusDescription></statusDescription> 



Open Compute Project  Open CloudServer chassis management specification 
http://opencompute.org 87 
  <apiVersion>1</apiVersion> 
  <bladeNumber<  
>1</bladeNumber>  
  </bladeResponse> 
  <bladeState>ON</bladeState>  
  </BladeStateResponse> 
9.6.16 Gets the Default Power State of All Blades 
GetAllBladesStateResponse GetAllBladesDefaultPowerState() 
https://localhost:8000/GetAllBladesDefaultPowerState? 
Usage scenario:  
The default power state of the blade is the state of the blade after it receives AC power, 
either when a blade is initially inserted in the slot or when power returns after a utility failure. 
If the default state is set to OFF, the blade will not be powered ON after receiving AC input 
power, and an explicit SetBladeActivePowerOn() API will need to be sent to power ON the 
blade. Note that the blade default power state does not affect the active power state of the 
blade; the default power state only affects the behavior after a power recycle. 
Note also that when multiple users are actively trying to access/modify the same state of a 
single blade or of different blades, ordering is not guaranteed. 
Input parameters: 
 None 
Sample response: 
- <GetAllBladesStateResponse 
xmlns="http://schemas.datacontract.org/2004/07/Microsoft.GFS.ACS.Contracts" 
xmlns:i="http://www.w3.org/2001/XMLSchema-instance"> 
- <BladeStateResponse> 
- <bladeResponse> 
  <completionCode>Success</completionCode>  
  <statusDescription></statusDescription> 
  <apiVersion>1</apiVersion> 
  <bladeNumber>1</bladeNumber>  
  </bladeResponse> 
  <bladeState>ON</bladeState>  
  </BladeStateResponse> 



 
88 January 28, 2014 
- <BladeStateResponse> 
- <bladeResponse> 
  <completionCode>Success</completionCode>  
  <statusDescription></statusDescription> 
  <apiVersion>1</apiVersion> 
  <bladeNumber>2</bladeNumber>  
  </bladeResponse> 
  <bladeState>ON</bladeState>  
  </BladeStateResponse> 
... 
- <BladeStateResponse> 
- <bladeResponse> 
  <completionCode>Success</completionCode>  
  <statusDescription></statusDescription> 
  <apiVersion>1</apiVersion> 
  <bladeNumber>24</bladeNumber>  
  </bladeResponse> 
  <bladeState>ON</bladeState>  
  </BladeStateResponse> 
  </GetAllBladesStateResponse> 
9.6.17 Gets Outlet Power State of Blade 
PowerStateResponse GetPowerState(int bladeId) 
https://localhost:8000/GetPowerState?bladeId=1 
Usage scenario:  
This API gets the AC outlet power state of a blade (whether or not the blade is receiving AC 
power).  
When ON, the blade is receiving AC power (hard-power state). When AC power is supplied to 
the blade and when the default power state of the blade is ON, the blade chipset will receive 
power and the boot process will be initiated. If the default power state of the blade is OFF 
when AC power is applied, the blade chipset will not receive power (and the boot process will 



Open Compute Project  Open CloudServer chassis management specification 
http://opencompute.org 89 
not be initiated) unless an explicit “SetBladeOn” command is sent to the blade.  
When OFF, the blade is not receiving AC power 
Input parameters: 
 bladeId (blade index 1-48) 
Sample response: 
<PowerStateResponse 
xmlns="http://schemas.datacontract.org/2004/07/Microsoft.GFS.ACS.Contracts" 
xmlns:i="http://www.w3.org/2001/XMLSchema-instance"> 
- <bladeResponse> 
  <completionCode>Success</completionCode>  
  <statusDescription></statusDescription> 
  <apiVersion>1</apiVersion> 
  <bladeNumber>1</bladeNumber>  
  </bladeResponse> 
  <powerState>ON</powerState>  
  </PowerStateResponse> 
9.6.18 Gets AC Outlet Power State of All Blades 
GetAllPowerStateResponse GetAllPowerState() 
https://localhost:8000/GetAllPowerState?  
Usage scenario:  
This API gets the AC outlet power state of all blades (whether or not the blades are receiving 
AC power). 
When ON, the blade is receiving AC power (hard-power state). When AC power is supplied to 
the blade and when the default power state of the blade is ON, the blade chipset will receive 
power and the boot process will be initiated. If the default power state of the blade is OFF 
when AC power is applied, the blade chipset will not receive power (and the boot process will 
not be initiated) unless an explicit “SetBladeOn” command is sent to the blade.  
When OFF, the blade is not receiving AC power. 
Note that when multiple users are actively trying to access/modify the same state of a single 
blade or of different blades, ordering is not guaranteed. 
Input parameters: 
 None 
Sample response: 
- < GetAllPowerStateResponse 



 
90 January 28, 2014 
xmlns="http://schemas.datacontract.org/2004/07/Microsoft.GFS.ACS.Contracts" 
xmlns:i="http://www.w3.org/2001/XMLSchema-instance"> 
- <PowerStateResponse> 
- <bladeResponse> 
  <completionCode>Success</completionCode>  
  <statusDescription></statusDescription> 
  <apiVersion>1</apiVersion> 
  <bladeNumber>1</bladeNumber>  
  </bladeResponse> 
  <powerState>ON</powerState>  
  </PowerStateResponse> 
- <PowerStateResponse> 
- <bladeResponse> 
  <completionCode>Success</completionCode>  
  <statusDescription></statusDescription> 
  <apiVersion>1</apiVersion> 
  <bladeNumber>2</bladeNumber>  
  </bladeResponse> 
  <powerState>ON</powerState>  
  </PowerStateResponse> 
... 
- <PowerStateResponse> 
- <bladeResponse> 
  <completionCode>Success</completionCode>  
  <statusDescription></statusDescription> 
  <apiVersion>1</apiVersion> 
  <bladeNumber>24</bladeNumber>  
  </bladeResponse> 
  <powerState>ON</powerState>  
  </PowerStateResponse> 
  </ GetAllPowerStateResponse> 



Open Compute Project  Open CloudServer chassis management specification 
http://opencompute.org 91 
9.6.19 Turns AC Outlet Power ON for Blade 
BladeResponse SetPowerOn(int bladeId) 
https://localhost:8000/SetPowerOn?bladeId=1 
Usage scenario:  
This API turns the AC power outlet power ON for a blade. 
When ON, the blade is receiving AC power (hard-power state). When AC power is supplied to 
the blade and when the default power state of the blade is ON, the blade chipset will receive 
power and the boot process will be initiated. If the default power state of the blade is OFF 
when AC power is applied, the blade chipset will not receive power (and the boot process will 
not be initiated) unless an explicit “SetBladeOn” command is sent to the blade.  
When OFF, the blade is not receiving AC power. 
Input parameters: 
 bladeId (blade index 1-48) 
Sample response: 
<BladeResponse 
xmlns="http://schemas.datacontract.org/2004/07/Microsoft.GFS.ACS.Contracts" 
xmlns:i="http://www.w3.org/2001/XMLSchema-instance"> 
  <completionCode>Success</completionCode>  
  <statusDescription></statusDescription> 
  <apiVersion>1</apiVersion> 
  <bladeNumber>1</bladeNumber>  
  </BladeResponse> 
9.6.20 Turns the AC Outlet Power ON for All Blades 
AllBladesResponse SetAllPowerOn() 
https://localhost:8000/SetAllPowerOn?  
Usage scenario:  
This API turns the AC power outlet ON for all blades. 
When ON, the blade is receiving AC power (hard-power state). When AC power is supplied to 
the blade and when the default power state of the blade is ON, the blade chipset will receive 
power and the boot process will be initiated. If the default power state of the blade is OFF 
when AC power is applied, the blade chipset will not receive power (and the boot process will 
not be initiated) unless an explicit “SetBladeOn” command is sent to the blade.  



 
92 January 28, 2014 
When OFF, the blade is not receiving AC power. 
Note that when multiple users are actively trying to access/modify the same state of a single 
blade or of different blades, ordering is not guaranteed. 
Input parameters: 
 None 
Sample response: 
- <AllBladesResponse 
xmlns="http://schemas.datacontract.org/2004/07/Microsoft.GFS.ACS.Contracts" 
xmlns:i="http://www.w3.org/2001/XMLSchema-instance"> 
- <BladeResponse> 
  <completionCode>Success</completionCode>  
  <statusDescription></statusDescription> 
  <apiVersion>1</apiVersion> 
  <bladeNumber>1</bladeNumber>  
  </BladeResponse> 
- <BladeResponse> 
  <completionCode>Success</completionCode>  
  <statusDescription></statusDescription> 
  <apiVersion>1</apiVersion> 
  <bladeNumber>2</bladeNumber>  
  </BladeResponse> 
... 
- <BladeResponse> 
  <completionCode>Success</completionCode>  
  <statusDescription></statusDescription> 
  <apiVersion>1</apiVersion> 
  <bladeNumber>24</bladeNumber>  
  </BladeResponse> 
  </AllBladesResponse> 
9.6.21 Turns AC Outlet Power OFF for Blade 



Open Compute Project  Open CloudServer chassis management specification 
http://opencompute.org 93 
BladeResponse SetPowerOff(int bladeId) 
https://localhost:8000/SetPowerOff?bladeId=1 
Usage scenario:  
This API turns the AC power OFF for a blade. 
When ON, the blade is receiving AC power (hard-power state). When AC power is supplied to 
the blade and when the default power state of the blade is ON, the blade chipset will receive 
power and the boot process will be initiated. If the default power state of the blade is OFF 
when AC power is applied, the blade chipset will not receive power (and the boot process will 
not be initiated) unless an explicit “SetBladeOn” command is sent to the blade.  
When OFF, the blade is not receiving AC power. 
Input parameters: 
 bladeId (blade index 1-48) 
Sample response: 
<BladeResponse 
xmlns="http://schemas.datacontract.org/2004/07/Microsoft.GFS.ACS.Contracts" 
xmlns:i="http://www.w3.org/2001/XMLSchema-instance"> 
  <completionCode>Success</completionCode>  
  <statusDescription></statusDescription> 
  <apiVersion>1</apiVersion> 
  <bladeNumber>1</bladeNumber>  
  </BladeResponse> 
9.6.22 Turns AC Outlet Power OFF for All Blades 
AllBladesResponse SetAllPowerOff() 
https://localhost:8000/SetAllPowerOff?  
Usage scenario:  
This API turns the AC power OFF for all blades. 
When ON, the blade is receiving AC power (hard-power state). When AC power is supplied to 
the blade and when the default power state of the blade is ON, the blade chipset will receive 
power and the boot process will be initiated. If the default power state of the blade is OFF 
when AC power is applied, the blade chipset will not receive power (and the boot process will 
not be initiated) unless an explicit “SetBladeOn” command is sent to the blade.  
When OFF, the blade is not receiving AC power. 



 
94 January 28, 2014 
Note that when multiple users are actively trying to access/modify the same state of a single 
blade or of different blades, ordering is not guaranteed. 
Input parameters: 
 None 
Sample response: 
- <AllBladesResponse 
xmlns="http://schemas.datacontract.org/2004/07/Microsoft.GFS.ACS.Contracts" 
xmlns:i="http://www.w3.org/2001/XMLSchema-instance"> 
  <completionCode>Success</completionCode>  
  <statusDescription></statusDescription> 
  <apiVersion>1</apiVersion> 
- <BladeResponse> 
  <completionCode>Success</completionCode>  
  <statusDescription></statusDescription> 
  <apiVersion>1</apiVersion> 
  <bladeNumber>1</bladeNumber>  
  </BladeResponse> 
- <BladeResponse> 
  <completionCode>Success</completionCode>  
  <statusDescription></statusDescription> 
  <apiVersion>1</apiVersion> 
  <bladeNumber>2</bladeNumber>  
  </BladeResponse> 
... 
- <BladeResponse> 
  <completionCode>Success</completionCode>  
  <statusDescription></statusDescription> 
  <apiVersion>1</apiVersion> 
  <bladeNumber>24</bladeNumber>  
  </BladeResponse> 
  </AllBladesResponse> 



Open Compute Project  Open CloudServer chassis management specification 
http://opencompute.org 95 
9.6.23 Gets the ON/OFF State of Blade 
BladeState GetBladeState(int bladeId) 
https://localhost:8000/GetBladeState?bladeId=1 
Usage scenario:  
This API is used to get the ON/OFF state of a blade (whether or not blade chipset is receiving 
power). 
When ON, the blade is receiving AC power (hard-power state) and the chipset is receiving 
power (soft-power state).  
When OFF, the blade chipset is not receiving power. 
Input parameters: 
 bladeId (blade index 1-48) 
Sample response: 
<BladeStateResponse 
xmlns="http://schemas.datacontract.org/2004/07/Microsoft.GFS.ACS.Contracts" 
xmlns:i="http://www.w3.org/2001/XMLSchema-instance"> 
- <bladeResponse> 
  <completionCode>Success</completionCode>  
  <statusDescription></statusDescription> 
  <apiVersion>1</apiVersion> 
  <bladeNumber>1</bladeNumber>  
  </bladeResponse> 
  <powerState>ON</powerState>  
  </BladeStateResponse> 
9.6.24 Gets the ON/OFF State of All Blades 
GetAllBladesStateResponse GetAllBladesState() 
https://localhost:8000/GetAllBladesState?  
Usage scenario:  
This API gets the ON/OFF state of all blades (whether or not blade chipsets are receiving 
power). 
When ON, the blades are receiving AC power (hard-power state) and the chipsets are 
receiving power (soft-power state).  



 
96 January 28, 2014 
When OFF, the blade chipsets are not receiving power. 
Note that when multiple users are actively trying to access/modify the same state of a single 
blade or of different blades, ordering is not guaranteed. 
Input parameters: 
 None 
Sample response: 
- <GetAllBladesStateResponse 
xmlns="http://schemas.datacontract.org/2004/07/Microsoft.GFS.ACS.Contracts" 
xmlns:i="http://www.w3.org/2001/XMLSchema-instance"> 
  <completionCode>Success</completionCode>  
  <statusDescription></statusDescription> 
  <apiVersion>1</apiVersion> 
- <BladeStateResponse> 
- <bladeResponse> 
  <completionCode>Success</completionCode>  
  <statusDescription></statusDescription> 
  <apiVersion>1</apiVersion> 
  <bladeNumber>1</bladeNumber>  
  </bladeResponse> 
  <powerState>ON</powerState>  
  </BladeStateResponse> 
- <BladeStateResponse> 
- <bladeResponse> 
  <completionCode>Success</completionCode>  
  <statusDescription></statusDescription> 
  <apiVersion>1</apiVersion> 
  <bladeNumber>2</bladeNumber>  
  </bladeResponse> 
  <powerState>ON</powerState>  
  </BladeStateResponse> 
... 
- <BladeStateResponse> 
- <bladeResponse> 



Open Compute Project  Open CloudServer chassis management specification 
http://opencompute.org 97 
  <completionCode>Success</completionCode>  
  <statusDescription></statusDescription> 
  <apiVersion>1</apiVersion> 
  <bladeNumber>24</bladeNumber>  
  </bladeResponse> 
  <powerState>ON</powerState>  
  </BladeStateResponse> 
  </GetAllBladesStateResponse> 
9.6.25 Supplies Power to the Blade Chipset 
BladeResponse SetBladeOn(int bladeId) 
https://localhost:8000/SetBladeOn?bladeId=1 
Usage scenario:  
This API is used to supply power to the blade chipset (initialize the boot process). 
When ON, the blade is receiving AC power (hard-power state) and the chipset is receiving 
power (soft-power state).  
When OFF, the blade chipset is not receiving power. 
Input parameters: 
 bladeId (blade index 1-48) 
Sample response: 
<BladeResponse 
xmlns="http://schemas.datacontract.org/2004/07/Microsoft.GFS.ACS.Contracts" 
xmlns:i="http://www.w3.org/2001/XMLSchema-instance"> 
  <completionCode>Success</completionCode>  
  <statusDescription></statusDescription> 
  <apiVersion>1</apiVersion> 
  <bladeNumber>1</bladeNumber>  
  </BladeResponse> 
9.6.26 Supplies Power to All Blade Chipsets 
AllBladesResponse SetAllBladesOn() 
https://localhost:8000/SetAllBladesOn?  



 
98 January 28, 2014 
Usage scenario:  
This API is used to supply power to the chipsets (initialize the boot process). 
When ON, the blades are receiving AC power (hard-power state) and the chipsets are 
receiving power (soft-power state).  
When OFF, the blade chipsets are not receiving power. 
Note that when multiple users are actively trying to access/modify the same state of a single 
blade or of different blades, ordering is not guaranteed. 
Input parameters: 
 None 
Sample response: 
- <AllBladesResponse 
xmlns="http://schemas.datacontract.org/2004/07/Microsoft.GFS.ACS.Contracts" 
xmlns:i="http://www.w3.org/2001/XMLSchema-instance"> 
  <completionCode>Success</completionCode>  
  <statusDescription></statusDescription> 
  <apiVersion>1</apiVersion> 
- <BladeResponse> 
  <completionCode>Success</completionCode>  
  <statusDescription></statusDescription> 
  <apiVersion>1</apiVersion> 
  <bladeNumber>1</bladeNumber>  
  </BladeResponse> 
- <BladeResponse> 
  <completionCode>Success</completionCode>  
  <statusDescription></statusDescription> 
  <apiVersion>1</apiVersion> 
  <bladeNumber>2</bladeNumber>  
  </BladeResponse> 
... 
- <BladeResponse> 
  <completionCode>Success</completionCode>  
  <statusDescription></statusDescription> 
  <apiVersion>1</apiVersion> 
  <bladeNumber>24</bladeNumber>  



Open Compute Project  Open CloudServer chassis management specification 
http://opencompute.org 99 
  </BladeResponse> 
  </AllBladesResponse> 
9.6.27 Stops Power to Blade Chipset 
BladeResponse SetBladeOff(int bladeId) 
https://localhost:8000/SetBladeOff?bladeId=1 
Usage scenario:  
This API is used to remove or stop power to the chipset. 
When ON, the blade is receiving AC power (hard-power state) and the chipset is receiving 
power (soft-power state).  
When OFF, the blade chipset is not receiving power. 
Input parameters: 
 bladeId (blade index 1-48) 
Sample response: 
<BladeResponse 
xmlns="http://schemas.datacontract.org/2004/07/Microsoft.GFS.ACS.Contracts" 
xmlns:i="http://www.w3.org/2001/XMLSchema-instance"> 
  <completionCode>Success</completionCode>  
  <statusDescription></statusDescription> 
  <apiVersion>1</apiVersion> 
  <bladeNumber>1</bladeNumber>  
  </BladeResponse> 
9.6.28 Stops Power to All Blade Chipsets 
AllBladesResponse SetAllBladesOff() 
https://localhost:8000/SetAllBladesOff?  
Usage scenario:  
This API is used to remove or turn OFF power to the chipsets. 
When ON, the blades are receiving AC power (hard-power state) and the chipsets are 
receiving power (soft-power state).  
When OFF, the blade chipsets are not receiving power. 
Note that when multiple users are actively trying to access/modify the same state of a single 
blade or of different blades, ordering is not guaranteed. 



 
100 January 28, 2014 
Input parameters: 
 None 
Sample response: 
- <AllBladesResponse 
xmlns="http://schemas.datacontract.org/2004/07/Microsoft.GFS.ACS.Contracts" 
xmlns:i="http://www.w3.org/2001/XMLSchema-instance"> 
  <completionCode>Success</completionCode>  
  <statusDescription></statusDescription> 
  <apiVersion>1</apiVersion> 
- <BladeResponse> 
  <completionCode>Success</completionCode>  
  <statusDescription></statusDescription> 
  <apiVersion>1</apiVersion> 
  <bladeNumber>1</bladeNumber>  
  </BladeResponse> 
- <BladeResponse> 
  <completionCode>Success</completionCode>  
  <statusDescription></statusDescription> 
  <apiVersion>1</apiVersion> 
  <bladeNumber>2</bladeNumber>  
  </BladeResponse> 
... 
- <BladeResponse> 
  <completionCode>Success</completionCode>  
  <statusDescription></statusDescription> 
  <apiVersion>1</apiVersion> 
  <bladeNumber>24</bladeNumber>  
  </BladeResponse> 
  </AllBladesResponse> 
9.6.29 Power Cycle Blade 



Open Compute Project  Open CloudServer chassis management specification 
http://opencompute.org 101 
BladeResponse SetBladeActivePowerCycle(int bladeId, uint offTime) 
https://localhost:8000/SetBladeActivePowerCycle?bladeId=1&offTime=0 
Usage scenario:  
This API is used to power cycle (or soft reset) a blade. 
Power cycle resets the blade (causing a software reboot sequence).  The blade AC power 
signal remains ON throughout the process. Any serial session active on that blade will 
continue to be active during this process.  
Input parameters: 
 bladeId (blade index 1-48) 
 offTime (time interval [in seconds] when the blade is powered off; if not specified, the 
default interval is 0 [optional]) 
Sample response: 
<BladeResponse 
xmlns="http://schemas.datacontract.org/2004/07/Microsoft.GFS.ACS.Contracts" 
xmlns:i="http://www.w3.org/2001/XMLSchema-instance"> 
  <completionCode>Success</completionCode>  
  <statusDescription></statusDescription> 
  <apiVersion>1</apiVersion> 
  <bladeNumber>1</bladeNumber>  
  </BladeResponse> 
9.6.30 Power Cycle All Blades 
AllBladesResponse SetAllBladesActivePowerCycle(uint offTime) 
https://localhost:8000/SetAllBladesActivePowerCycle?offTime=0  
Usage scenario:  
This API power cycles (or soft resets) all blades. 
Power cycle resets the blade (causing a software reboot sequence).  The blade AC power 
signal remains ON throughout the process. Any serial session active on that blade will 
continue to be active during this process.  
Note that when multiple users are actively trying to access/modify the same state of a single 
blade or of different blades, ordering is not guaranteed. 
Input parameters: 
 offTime (time interval [in seconds] when the blade is powered off; if not specified, the 
default interval is 0 [optional]) 
Sample response: 



 
102 January 28, 2014 
- <AllBladesResponse 
xmlns="http://schemas.datacontract.org/2004/07/Microsoft.GFS.ACS.Contracts" 
xmlns:i="http://www.w3.org/2001/XMLSchema-instance"> 
  <completionCode>Success</completionCode>  
  <statusDescription></statusDescription> 
  <apiVersion>1</apiVersion> 
- <BladeResponse> 
  <completionCode>Success</completionCode>  
  <statusDescription></statusDescription> 
  <apiVersion>1</apiVersion> 
  <bladeNumber>1</bladeNumber>  
  </BladeResponse> 
- <BladeResponse> 
  <completionCode>Success</completionCode>  
  <statusDescription></statusDescription> 
  <apiVersion>1</apiVersion> 
  <bladeNumber>2</bladeNumber>  
  </BladeResponse> 
... 
- <BladeResponse> 
  <completionCode>Success</completionCode>  
  <statusDescription></statusDescription> 
  <apiVersion>1</apiVersion> 
  <bladeNumber>24</bladeNumber>  
  </BladeResponse> 
  </AllBladesResponse> 
9.6.31 Turns Chassis AC Sockets (TOR Switches) ON 
ChassisResponse SetACSocketPowerStateOn(uint portNo) 
https://localhost:8000/SetACSocketPowerStateOn?portNo=1 
Usage scenario:  



Open Compute Project  Open CloudServer chassis management specification 
http://opencompute.org 103 
This API turns the chassis AC sockets (TOR switches) ON. 
The AC socket power state refers to the active power state of the COM ports (and therefore 
to the power state of the device connected to the port) on the chassis manager. For example, 
the TOR switch is connected to COM1 (port number 1). 
Power ON/OFF APIs for the AC sockets makes it possible to remotely power-reset the device 
The power ON/OFF APIs are also used for enabling/disabling.  
Input parameters: 
 portNo (port number of the AC socket) 
Sample response: 
<ChassisResponse 
xmlns="http://schemas.datacontract.org/2004/07/Microsoft.GFS.ACS.Contracts" 
xmlns:i="http://www.w3.org/2001/XMLSchema-instance"> 
  <completionCode>Success</completionCode>  
  <statusDescription></statusDescription> 
  <apiVersion>1</apiVersion> 
  </ChassisResponse> 
9.6.32 Turns Chassis AC Sockets (TOR Switches) OFF 
ChassisResponse SetACSocketPowerStateOff(uint portNo) 
https://localhost:8000/SetACSocketPowerStateOff?portNo=2 
Usage scenario:  
This API turns the chassis AC sockets (TOR switches) OFF. 
The AC socket power state refers to the active power state of the COM ports (and therefore 
to the power state of the device connected to the port) on the chassis manager. For example, 
the TOR switch is connected to COM1 (port number 1). 
Power ON/OFF APIs for the AC sockets makes it possible to remotely power-reset the device 
The power ON/OFF APIs are also used for enabling/disabling.  
Input parameters: 
 portNo (port number of the AC socket) 
Sample response: 
<ChassisResponse 
xmlns="http://schemas.datacontract.org/2004/07/Microsoft.GFS.ACS.Contracts" 
xmlns:i="http://www.w3.org/2001/XMLSchema-instance"> 
  <completionCode>Success</completionCode>  
  <statusDescription></statusDescription> 



 
104 January 28, 2014 
  <apiVersion>1</apiVersion> 
  </ChassisResponse> 
9.6.33 Gets Status of Chassis AC Sockets (TOR Switches)  
ACSocketStateResponse GetACSocketPowerState(uint portNo) 
https://localhost:8000/GetACSocketPowerState?portNo=1 
Usage scenario:  
This API gets the status of the chassis AC sockets (TOR switches).  
The AC socket power state refers to the active power state of the COM ports (and therefore 
to the power state of the device connected to the port) on the chassis manager. For example, 
the TOR switch is connected to COM1 (port number 1). 
Power ON/OFF APIs for the AC sockets makes it possible to remotely power-reset the device 
The power ON/OFF APIs are also used for enabling/disabling.  
Input parameters: 
 portNo (port number of the AC socket) 
Sample response: 
<ACSocketStateResponse 
xmlns="http://schemas.datacontract.org/2004/07/Microsoft.GFS.ACS.Contracts" 
xmlns:i="http://www.w3.org/2001/XMLSchema-instance"> 
  <completionCode>Success</completionCode>  
  <statusDescription></statusDescription> 
  <apiVersion>1</apiVersion> 
  <portNo>1</portNo>  
  <powerState>ON</powerState>  
  </ACSocketStateResponse> 
9.6.34 Starts Serial Session to Blade 
StartSerialResponse StartBladeSerialSession(int bladeId) 
https://localhost:8000/StartBladeSerialSessions?bladeId=1 
Usage scenario:  
This API starts a serial session to a blade. 
Users might want to open a serial session to a blade to debug, to view blade boot messages, 



Open Compute Project  Open CloudServer chassis management specification 
http://opencompute.org 105 
or to execute BIOS commands. A provided VT100 console client continuously polls the blade 
for serial session data (using the ReceiveBladeSerialData API). Any user command entered 
using the VT100 console is sent to the blade (using the SendBladeSerialData API). 
Note that this session might close unexpectedly if there are any simultaneous IPMI 
commands issued to any of the chassis blades or if the session is inactive (no 
SendBladeSerialData request from client) for more than two minutes.  
Input parameters: 
 bladeId (blade index 1-48) 
Sample response: 
StartSerialResponse.sessionToken: 11234 
StartSerialResponse.CompletionCode: success 
9.6.35 Stop Serial Session to Blade 
ChassisResponse  StopBladeSerialSession(int bladeId, string sessionToken, bool 
forceKill=false)  
https://localhost:8000/StopBladeSerialSessions?bladeId=1 
Usage scenario:  
This API stops a serial session to a blade. 
Users might want to open a serial session to a blade to debug, to view blade boot messages, 
or to execute BIOS commands. A provided VT100 console client continuously polls the blade 
for serial session data (using the ReceiveBladeSerialData API). Any user command entered 
using the VT100 console is sent to the blade (using the SendBladeSerialData API). 
Note that this session might close unexpectedly if there are any simultaneous IPMI 
commands issued to any of the chassis blades (when the config. parameter forceKill is set to 
true) or if the session is inactive (no SendBladeSerialData request from client) for more than 
two minutes.  However, when forceKill is set to false, an already existing blade serial console 
session will not be interrupted, and an incoming IPMI command will be ignored. 
 
 
Input parameters: 
 bladeId (blade index 1-48) 
 sessionToken (generated as part of the StartBladeSerialSession API) 
 forceKill (true or false with semantics explained above) 
Sample response:   
  <completionCode>Success</completionCode>  



 
106 January 28, 2014 
  <statusDescription></statusDescription> 
9.6.36 Sends Data to Blade Serial Device 
ChassisResponse SendBladeSerialData(int bladeId, string sessionToken, byte[] data) 
https://localhost:8000/SendBladeSerialData?bladeId=1?sessionToken? 
Usage scenario:  
This API sends the data entered by user on the serial console to the blade serial device 
(internal API used by the serial-client-proxy) 
Users might want to open a serial session to a blade to debug, to view blade boot messages, 
or to execute BIOS commands. A provided VT100 console client continuously polls the blade 
for serial session data (using the ReceiveBladeSerialData API). Any user command entered 
using the VT100 console is sent to the blade (using the SendBladeSerialData API). 
Note that this session might close unexpectedly if there are any simultaneous IPMI 
commands issued to any of the chassis blades or if the session is inactive (no 
SendBladeSerialData request from client) for more than two minutes.  
Input parameters: 
 bladeId (blade index 1-48) 
 sessionToken (generated as part of the StartBladeSerialSession API) 
 data (data to be sent) 
Sample response: 
ChassisResponse .completionCode: Success 
9.6.37 Receives Data from Blade 
SerialDataResponse ReceiveBladeSerialData(int bladeId, string sessionToken) 
https://localhost:8000/ReceiveBladeSerialData?bladeId=1?sessionToken? 
Usage scenario:  
This API receives data from the blade (internal API used by the serial-client-proxy). 
Users might want to open a serial session to a blade to debug, to view blade boot messages, 
or to execute BIOS commands. A provided VT100 console client continuously polls the blade 
for serial session data (using the ReceiveBladeSerialData API). Any user command entered 
using the VT100 console is sent to the blade (using the SendBladeSerialData API). 
Note that this session might close unexpectedly if there are any simultaneous IPMI 
commands issued to any of the chassis blades or if the session is inactive (no 
SendBladeSerialData request from client) for more than two minutes.  



Open Compute Project  Open CloudServer chassis management specification 
http://opencompute.org 107 
Input parameters: 
 bladeId (blade index 1-48) 
 sessionToken (token id generated as part of the StartBladeSerialSession API) 
Sample response: 
SerialDataResponse .bladeResponse.bladeCompletionCode: Success 
SerialDataResponse .data 
9.6.38 Starts Serial Port Console 
StartSerialResponse StartSerialPortConsole(string portId) 
https://localhost:8000/StartSerialPortConsole?PorId=3 
Usage scenario:  
This API is used to open a serial-port console terminal to serial devices that are connected to 
the chassis manager (for example, TOR network switches). Note that the serial console might 
close if session is inactive (no SendSerialPortData request from client) for more than two 
minutes.  
A provided VT100 console client continuously polls the serial device for data (using the 
ReceiveSerialPortData API). Any user command entered using the VT100 console is sent to 
the device (using the SendSerialPortData API). 
Input parameters: 
 portId (com1-com2) 
Sample response: 
StartSerialResponse.sessionToken: 32656 
StartSerialResponse.CompletionCode: success 
9.6.39 Stops Serial Port Console 
StartSerialResponse StopSerialPortConsole(string portId, string sessionToken, bool 
forceKill) 
https://localhost:8000/StopSerialPortConsole?PorId=1 
Usage scenario:  
This API is used to close a serial-port console terminal to serial devices that are connected to 
the chassis manager (for example, TOR network switches). Note that the serial console might 
close if session is inactive (no SendSerialPortData request from client) for more than two 
minutes.  
A provided VT100 console client continuously polls the serial device for data (using the 
ReceiveSerialPortData API). Any user command entered using the VT100 console is sent to 



 
108 January 28, 2014 
the device (using the SendSerialPortData API). 
Input parameters: 
 portId (com1-com2) 
 sessionToken 
 forceKill 
Sample response: 
ChassisResponse.CompletionCode: success 
9.6.40 Sends Serial Port Data 
ChassisResponse SendSerialPortData(string portId, string sessionToken, byte[] data) 
https://localhost:8000/SendSerialPortData?portId=1?sessionToken? 
Sends the serial data to the blade 
Usage scenario: 
This is an internal API used for sending data from the user serial-client terminal to serial 
devices connected to the chassis manager (for example, user commands executed on the TOR 
network switch serial console). Note that the serial console might close if session is inactive 
(no SendSerialPortData request from client) for more than two minutes. 
A provided VT100 console client continuously polls the serial device for data (using the 
ReceiveSerialPortData API). Any user command entered using the VT100 console is sent to 
the device (using the SendSerialPortData API). 
Input parameters:  
 portId (com1-com2) 
 sessionToken (token id) 
 data (data to be sent) 
Sample response: 
ChassisResponse.CompletionCode: Success 
9.6.41 Receives Serial Port Data 
SerialDataResponse ReceiveSerialPortData(string portId, string sessionToken) 
https://localhost:8000/ReceiveSerialPortData?portId=1?sessionToken? 
Usage scenario: 
This is an internal API used for receiving data on the terminal from serial devices connected 
to the chassis manager (for example, user commands executed on the TOR network switch 
serial console). Note that the serial console might close if session is inactive(no 



Open Compute Project  Open CloudServer chassis management specification 
http://opencompute.org 109 
SendSerialPortData request from client) for more than two minutes. 
A provided VT100 console client continuously polls the serial device for data (using the 
ReceiveSerialPortData API). Any user command entered using the VT100 console is sent to 
the device (using the SendSerialPortData API). 
Input parameters:  
 portId (com1-com2) 
 sessionToken  (token id) 
Sample response: 
ChassisResponse.CompletionCode: Success 
SerialData.data 
9.6.42 Reads the Chassis Log (with timestamp parameter) 
LogResponse ReadChassisLog() 
LogResponse ReadChassisLogWithTimestamp(Datetime startTimestamp, Datetime 
endTimestamp) 
https://localhost:8000/ReadChassisLog? 
Usage scenario: 
This API reads the chassis log. 
The chassis log contains information about the various alerts and warning messages 
associated with devices connected to the chassis manager (for example, blades overheating, 
and fan/PSU failure). The chassis log also contains user audit information, such as 
timestamp/activity performed by the user. 
Input parameters:  
 startTimestamp (read log from the start timestamp, optional) 
 endTimestamp (read log till the given end timestamp, optional) 
Sample response: 
- <ChassisLogResponse 
xmlns="http://schemas.datacontract.org/2004/07/Microsoft.GFS.ACS.Contracts" 
xmlns:i="http://www.w3.org/2001/XMLSchema-instance"> 
  <completionCode>Success</completionCode>  
  <statusDescription></statusDescription> 
  <apiVersion>1</apiVersion> 
- <logEntries> 
- <LogEntry> 
  <eventDescription><user>,Invoked </eventDescription>  
  <eventTime>2012-09-11T21:04:33.024</eventTime>  



 
110 January 28, 2014 
  </LogEntry> 
- <LogEntry> 
  <eventDescription><user>,Invoked </eventDescription>  
  <eventTime>2012-09-11T21:04:33.117</eventTime>  
  </LogEntry> 
... 
- <LogEntry> 
  <eventDescription><user>,Invoked ReadChassisLog()</eventDescription>  
  <eventTime>2012-09-11T21:20:03.366</eventTime>  
  </LogEntry> 
  </logEntries> 
  </ChassisLogResponse> 
9.6.43 Clears the Chassis Log 
ClearResponse ClearChassisLog() 
https://localhost:8000/ClearChassisLog? 
Usage scenario: 
This API clears the chassis log. Users must periodically clear the consumed log entries 
because there are size restrictions on the chassis manager storage space. 
Input parameters:  
 None 
Sample response: 
<ChassisResponse 
xmlns="http://schemas.datacontract.org/2004/07/Microsoft.GFS.ACS.Contracts" 
xmlns:i="http://www.w3.org/2001/XMLSchema-instance"> 
  <completionCode>Success</completionCode>  
  <statusDescription></statusDescription> 
  <apiVersion>1</apiVersion> 
  </ChassisResponse> 
9.6.44 Reads Log from Blade (with timestamp parameter) 



Open Compute Project  Open CloudServer chassis management specification 
http://opencompute.org 111 
LogResponse ReadBladeLog(int bladeId) 
LogResponse ReadBladeLogWithTimestamp(int bladeId, uint logType, Datetime 
startTimestamp, Datetime endTimestamp) 
https://localhost:8000/ReadBladeLog?bladeId=1 
Usage scenario: 
This API reads the log of a blade. Blade logs (system event logs) contain information about 
events, warning, and alerts pertaining to that blade (for example, thermal throttling of blades 
because of overheating). 
Input parameters:  
 bladeId (blade index, 1-48) 
 startTimestamp (read log from this given start timestamp, optional) 
 endTimestamp (read log till the given end timestamp, optional) 
Sample response: 
- <ChassisLogResponse 
xmlns="http://schemas.datacontract.org/2004/07/Microsoft.GFS.ACS.Contracts" 
xmlns:i="http://www.w3.org/2001/XMLSchema-instance"> 
  <completionCode>Failure</completionCode>  
  <statusDescription>The CM did not respond</statusDescription> 
  <apiVersion>1</apiVersion> 
- <logEntries> 
- <LogEntry> 
  <eventDescription>Sensor_SpecificDrive_Slot2433328Assertion111</eventDescription>  
  <eventTime>2012-08-23T14:35:21</eventTime>  
  </LogEntry> 
- <LogEntry> 
  <eventDescription>Sensor_SpecificDrive_Slot2443328Assertion111</eventDescription>  
  <eventTime>2012-08-23T14:35:21</eventTime>  
  </LogEntry> 
... 
- <LogEntry> 
  <eventDescription>DiscreteTemperature187257Desertion3</eventDescription>  
  <eventTime>2012-08-23T16:11:08</eventTime>  
  </LogEntry> 
  </logEntries> 
  </ChassisLogResponse> 



 
112 January 28, 2014 
9.6.45 Clears Log from Blade 
BladeResponse ClearBladelog(int bladeId) 
https://localhost:8000/ClearBladeLog?bladeId=1 
Usage scenario: 
This API clears the log from a blade. 
Blade logs (system event logs) contain information about events, warning, and alerts 
pertaining to that blade (for example, thermal throttling of blades because of overheating). 
Input parameters:  
 bladeId  (blade index, 1-48) 
Sample response: 
- <BladeResponse 
xmlns="http://schemas.datacontract.org/2004/07/Microsoft.GFS.ACS.Contracts" 
xmlns:i="http://www.w3.org/2001/XMLSchema-instance"> 
  <completionCode>Success</completionCode>  
  <statusDescription></statusDescription> 
  <apiVersion>1</apiVersion> 
  <bladeNumber>1</bladeNumber>  
  </BladeResponse> 
9.6.46 Gets Power Reading from Blade 
BladePowerReadingResponse  GetBladePowerReading(int bladeId) 
https://localhost:8000/GetBladePowerReading?bladeId=1 
Usage scenario: 
This API is used to get the power reading of a blade. It can be used for monitoring or for 
other power-control mechanisms (see the SetBladePowerLimit() API). 
Input parameters:  
 bladeId (blade index, 1-48) 
Sample response: 
- <BladePowerReadingResponse 
xmlns="http://schemas.datacontract.org/2004/07/Microsoft.GFS.ACS.Contracts" 
xmlns:i="http://www.w3.org/2001/XMLSchema-instance"> 
  <completionCode>Success</completionCode>  
  <statusDescription></statusDescription> 



Open Compute Project  Open CloudServer chassis management specification 
http://opencompute.org 113 
  <apiVersion>1</apiVersion> 
- <bladeResponse> 
  <completionCode>Success</completionCode>  
  <statusDescription></statusDescription> 
  <apiVersion>1</apiVersion> 
  <bladeNumber>1</bladeNumber>  
  </bladeResponse> 
  <powerReading>308</powerReading>  
  </BladePowerReadingResponse> 
9.6.47 Gets Power Readings from All Blades 
GetAllBladesPowerReadingResponse GetAllBladesPowerReading() 
https://localhost:8000/GetAllBladesPowerReading? 
Usage scenario: 
This API can be used for monitoring or for other power-control mechanisms (see the 
SetBladePowerLimit() API). 
Note that when multiple users are actively trying to access/modify the same state of a single 
blade or of different blades, ordering is not guaranteed. 
Input parameters:  
 None 
Sample response: 
- <GetAllBladesPowerReadingResponse 
xmlns="http://schemas.datacontract.org/2004/07/Microsoft.GFS.ACS.Contracts" 
xmlns:i="http://www.w3.org/2001/XMLSchema-instance"> 
- <BladePowerReadingResponse> 
  <completionCode>Success</completionCode>  
  <statusDescription></statusDescription> 
  <apiVersion>1</apiVersion> 
- <bladeResponse> 
  <completionCode>Success</completionCode>  
  <statusDescription></statusDescription> 
  <apiVersion>1</apiVersion> 
  <bladeNumber>1</bladeNumber>  



 
114 January 28, 2014 
  </bladeResponse> 
  <powerReading>308</powerReading>  
  </BladePowerReadingResponse> 
- <BladePowerReadingResponse> 
  <completionCode>Success</completionCode>  
  <statusDescription></statusDescription> 
  <apiVersion>1</apiVersion> 
- <bladeResponse> 
  <completionCode>Success</completionCode>  
  <statusDescription></statusDescription> 
  <apiVersion>1</apiVersion> 
  <bladeNumber>2</bladeNumber>  
  </bladeResponse> 
  <powerReading>311</powerReading>  
  </BladePowerReadingResponse> 
... 
- <BladePowerReadingResponse> 
  <completionCode>Success</completionCode>  
  <statusDescription></statusDescription> 
  <apiVersion>1</apiVersion> 
- <bladeResponse> 
  <completionCode>Success</completionCode>  
  <statusDescription></statusDescription> 
  <apiVersion>1</apiVersion> 
  <bladeNumber>24</bladeNumber>  
  </bladeResponse> 
  <powerReading>310</powerReading>  
  </BladePowerReadingResponse> 
  </GetAllBladesPowerReadingResponse> 



Open Compute Project  Open CloudServer chassis management specification 
http://opencompute.org 115 
9.6.48 Gets Power Limit of Blade 
GetBladeLimitResponse GetBladePowerLimit(int bladeId) 
https://localhost:8000/GetBladePowerLimit?bladeId=1 
Usage scenario: 
This API can be used to get the power limit that is set on a particular blade. 
Input parameters:  
 bladeId  (blade index, 1-48) 
Sample response: 
- <BladePowerLimitResponse 
xmlns="http://schemas.datacontract.org/2004/07/Microsoft.GFS.ACS.Contracts" 
xmlns:i="http://www.w3.org/2001/XMLSchema-instance"> 
  <completionCode>Success</completionCode>  
  <statusDescription></statusDescription> 
  <apiVersion>1</apiVersion> 
- <bladeResponse> 
  <completionCode>Success</completionCode>  
  <statusDescription></statusDescription> 
  <apiVersion>1</apiVersion> 
  <bladeNumber>1</bladeNumber>  
  </bladeResponse> 
  <powerReading>750</powerReading>  
  </BladePowerLimitResponse> 
9.6.49 Gets Power Limit of All Blades 
GetAllBladesPowerLimitResponse GetAllBladesPowerLinit() 
https://localhost:8000/GetAllBladesPowerLimit? 
Usage scenario: 
This API can be used to get the power limit that is set on all blades in a chassis. 
Note: When multiple users are actively trying to access/modify the same state of a single 
blade or of different blades, ordering is not guaranteed. 
Input parameters:  
 None 



 
116 January 28, 2014 
Sample response: 
- <GetAllBladesPowerLimitResponse 
xmlns="http://schemas.datacontract.org/2004/07/Microsoft.GFS.ACS.Contracts" 
xmlns:i="http://www.w3.org/2001/XMLSchema-instance"> 
- <BladePowerLimitResponse> 
  <completionCode>Success</completionCode>  
  <statusDescription></statusDescription> 
  <apiVersion>1</apiVersion> 
- <bladeResponse> 
  <completionCode>Success</completionCode>  
  <statusDescription></statusDescription> 
  <apiVersion>1</apiVersion> 
  <bladeNumber>1</bladeNumber>  
  </bladeResponse> 
  <powerReading>750</powerReading>  
  </BladePowerLimitResponse> 
- <BladePowerLimitResponse> 
  <completionCode>Success</completionCode>  
  <statusDescription></statusDescription> 
  <apiVersion>1</apiVersion> 
- <bladeResponse> 
  <completionCode>Success</completionCode>  
  <statusDescription></statusDescription> 
  <apiVersion>1</apiVersion> 
  <bladeNumber>2</bladeNumber>  
  </bladeResponse> 
  <powerReading>750</powerReading>  
  </BladePowerLimitResponse> 
... 
- <BladePowerLimitResponse> 
  <completionCode>Success</completionCode>  
  <statusDescription></statusDescription> 



Open Compute Project  Open CloudServer chassis management specification 
http://opencompute.org 117 
  <apiVersion>1</apiVersion> 
- <bladeResponse> 
  <completionCode>Success</completionCode>  
  <statusDescription></statusDescription> 
  <apiVersion>1</apiVersion> 
  <bladeNumber>24</bladeNumber>  
  </bladeResponse> 
  <powerReading>750</powerReading>  
  </BladePowerLimitResponse> 
  </GetAllBladesPowerLmitResponse> 
9.6.50 Sets Power Limit on Blade 
BladeResponse SetBladePowerLimit(int bladeId, double powerLimitInWatts) 
https://localhost:8000/SetBladePowerLimit?bladeId=1&powerLimitInWatts=750  
Usage scenario: 
This API is used to set the power limit for a blade; if the user wants to set the same power 
limit for all the blades, the SetAllBladesPowerLimit() API can be used. SetBladePowerLimitOn 
API has to be executed to actually realize the set power limit in the device. 
 
Power limits can be set for a variety of reasons, including energy savings and under-
provisioning (consolidating more servers under a power hierarchy). 
Input parameters:  
 bladeId (blade index 1-48 
 powerLimitInWatts  
Sample response: 
- <BladeResponse 
xmlns="http://schemas.datacontract.org/2004/07/Microsoft.GFS.ACS.Contracts" 
xmlns:i="http://www.w3.org/2001/XMLSchema-instance"> 
  <completionCode>Success</completionCode>  
  <statusDescription></statusDescription> 
  <apiVersion>1</apiVersion> 
  <bladeNumber>1</bladeNumber>  
  </BladeResponse> 



 
118 January 28, 2014 
9.6.51 Sets Power Limit on All Blades 
AllBladesResponse  SetAllBladesPowerLimit(double powerLimitInWatts) 
https://localhost:8000/SetAllBladesPowerLimit?powerLimitInWatts=750  
Usage scenario: 
This API is used to set the power limit for all blades in a chassis; if the user wants to set 
heterogeneous power limits, the SetBladePowerLimit() API can be used Power limits can be 
set for a variety of reasons, including energy savings and under-provisioning (consolidating 
more servers under a power hierarchy). SetBladePowerLimitOn API has to be executed to 
actually realize the set power limit in the device. 
Note that when multiple users are actively trying to access/modify the same state of a single 
blade or of different blades, ordering is not guaranteed. 
Input parameters:  
 powerLimitInWatts  
Sample response: 
- <AllBladesResponse 
xmlns="http://schemas.datacontract.org/2004/07/Microsoft.GFS.ACS.Contracts" 
xmlns:i="http://www.w3.org/2001/XMLSchema-instance"> 
  <completionCode>Success</completionCode>  
  <statusDescription></statusDescription> 
  <apiVersion>1</apiVersion> 
- <BladeResponse> 
  <completionCode>Success</completionCode>  
  <statusDescription></statusDescription> 
  <apiVersion>1</apiVersion> 
  <bladeNumber>1</bladeNumber>  
  </BladeResponse> 
- <BladeResponse> 
  <completionCode>Success</completionCode>  
  <statusDescription></statusDescription> 
  <apiVersion>1</apiVersion> 
  <bladeNumber>2</bladeNumber>  
  </BladeResponse> 
... 



Open Compute Project  Open CloudServer chassis management specification 
http://opencompute.org 119 
- <BladeResponse> 
  <completionCode>Success</completionCode>  
  <statusDescription></statusDescription> 
  <apiVersion>1</apiVersion> 
  <bladeNumber>24</bladeNumber>  
  </BladeResponse> 
  </AllBladesResponse> 
9.6.52 Activates Blade Power Limit 
BladeResponse SetBladePowerLimitOn(int bladeId) 
https://localhost:8000/SetBladePowerLimitOn?bladeId=1  
Usage scenario: 
This API activates the power limit for a blade and enables power throttling.  
Power limits can be set for a variety of reasons, including energy savings and under-
provisioning (consolidating more servers under a power hierarchy). 
Input parameters:  
 bladeId (blade index 1-48 
Sample response: 
<BladeResponse 
xmlns="http://schemas.datacontract.org/2004/07/Microsoft.GFS.ACS.Contracts" 
xmlns:i="http://www.w3.org/2001/XMLSchema-instance"> 
  <completionCode>Success</completionCode>  
  <statusDescription></statusDescription> 
  <apiVersion>1</apiVersion> 
  <bladeNumber>1</bladeNumber>  
  </BladeResponse> 
9.6.53 Activates Power Limit on All Blades 
AllBladesResponse  SetAllBladesPowerLimitOn() 
https://localhost:8000/SetAllBladesPowerLimitOn?   
Usage scenario: 
This API activates the power limit for all blades in a chassis and enables power throttling. 



 
120 January 28, 2014 
Power limits can be set for a variety of reasons, including energy savings and under-
provisioning (consolidating more servers under a power hierarchy). 
Input parameters:  
 None 
Sample response: 
- <AllBladesResponse 
xmlns="http://schemas.datacontract.org/2004/07/Microsoft.GFS.ACS.Contracts" 
xmlns:i="http://www.w3.org/2001/XMLSchema-instance"> 
  <completionCode>Success</completionCode>  
  <statusDescription></statusDescription> 
  <apiVersion>1</apiVersion> 
- <BladeResponse> 
  <completionCode>Success</completionCode>  
  <statusDescription></statusDescription> 
  <apiVersion>1</apiVersion> 
  <bladeNumber>1</bladeNumber>  
  </BladeResponse> 
- <BladeResponse> 
  <completionCode>Success</completionCode>  
  <statusDescription></statusDescription> 
  <apiVersion>1</apiVersion> 
  <bladeNumber>2</bladeNumber>  
  </BladeResponse> 
... 
- <BladeResponse> 
  <completionCode>Success</completionCode>  
  <statusDescription></statusDescription> 
  <apiVersion>1</apiVersion> 
  <bladeNumber>24</bladeNumber>  
  </BladeResponse> 
  </AllBladesResponse> 



Open Compute Project  Open CloudServer chassis management specification 
http://opencompute.org 121 
9.6.54 Deactivates Blade Power Limit 
BladeResponse SetBladePowerLimitOff(int bladeId) 
https://localhost:8000/SetBladePowerLimitOff?bladeId=1  
Usage scenario: 
This API deactivates the power limit for a blade and disables power throttling. 
Power limits can be set for a variety of reasons, including energy savings and under-
provisioning (consolidating more servers under a power hierarchy). 
Input parameters:  
 bladeId (blade index 1-48) 
Sample response: 
<BladeResponse 
xmlns="http://schemas.datacontract.org/2004/07/Microsoft.GFS.ACS.Contracts" 
xmlns:i="http://www.w3.org/2001/XMLSchema-instance"> 
  <completionCode>Success</completionCode>  
  <statusDescription></statusDescription> 
  <apiVersion>1</apiVersion> 
  <bladeNumber>1</bladeNumber>  
  </BladeResponse> 
9.6.55 Deactivates Power Limit on All Blades 
AllBladesResponse  SetAllBladesPowerLimitOff() 
https://localhost:8000/SetAllBladesPowerLimitOff?   
Usage scenario: 
This API deactivates the power limit for all blades in a chassis and disables power throttling. 
Power limits can be set for a variety of reasons, including energy savings and under-
provisioning (consolidating more servers under a power hierarchy). 
Input parameters:  
 None 
Sample response: 
- <AllBladesResponse 
xmlns="http://schemas.datacontract.org/2004/07/Microsoft.GFS.ACS.Contracts" 
xmlns:i="http://www.w3.org/2001/XMLSchema-instance"> 
  <completionCode>Success</completionCode>  



 
122 January 28, 2014 
  <statusDescription></statusDescription> 
  <apiVersion>1</apiVersion> 
- <BladeResponse> 
  <completionCode>Success</completionCode>  
  <statusDescription></statusDescription> 
  <apiVersion>1</apiVersion> 
  <bladeNumber>1</bladeNumber>  
  </BladeResponse> 
- <BladeResponse> 
  <completionCode>Success</completionCode>  
  <statusDescription></statusDescription> 
  <apiVersion>1</apiVersion> 
  <bladeNumber>2</bladeNumber>  
  </BladeResponse> 
... 
- <BladeResponse> 
  <completionCode>Success</completionCode>  
  <statusDescription></statusDescription> 
  <apiVersion>1</apiVersion> 
  <bladeNumber>24</bladeNumber>  
  </BladeResponse> 
  </AllBladesResponse> 
9.6.56 Gets Chassis Controller Network Properties 
ChassisNetworkPropertiesResponse GetChassisNetworkProperties() 
https://localhost:8000/GetChassisNetworkProperties?  
Usage scenario: 
This API gets the chassis controller network properties including MAC address, IP address, 
subnet mask, DHCP Enabled/Disabled. 
Note that Microsoft does not support setting network properties of the chassis manager and 
encourages users to use standard Windows interface/APIs for this. 



Open Compute Project  Open CloudServer chassis management specification 
http://opencompute.org 123 
Input parameters:  
 None 
Sample response: 
- <ChassisNetworkPropertiesResponse 
xmlns="http://schemas.datacontract.org/2004/07/Microsoft.GFS.ACS.Contracts" 
xmlns:i="http://www.w3.org/2001/XMLSchema-instance"> 
  <completionCode>Success</completionCode>  
  <statusDescription></statusDescription> 
  <apiVersion>1</apiVersion> 
- <ChassisNetworkProperty> 
<completionCode>Success</completionCode>  
  <statusDescription></statusDescription> 
  <apiVersion>1</apiVersion> 
  <ipAddress>xxx.xxx.xxx.xx</ipAddress>  
  <macAddress>xx:xx:xx:xx:xx:xx</macAddress>  
  <dhcpEnabled>true</dhcpEnabled>  
  <dhcpServer>xxx.xxx.xxx.x</dhcpServer>  
  <dnsAddress i:nil="true" />  
  <dnsDomain>XXX.lab</dnsDomain>  
  <dnsHostName>MACHINE1</dnsHostName>  
  <gatewayAddress i:nil="true" />  
  <subnetMask>xxx.xxx.xxx.x</subnetMask>  
  </ChassisNetworkProperty> 
  </ChassisNetworkPropertiesResponse> 
9.6.57 Adds New Chassis Controller User 
ChassisResponse AddChassisControllerUser(string userName, string passwordString, 
ACSSecurityRole role) 
https://localhost:8000/AddChassisControllerUser?userName=xxx&passwordString
=yyyy&role=1  
Usage scenario: 
This API is used to add a new chassis controller user with a specified password with privileges 
for accessing the chassis manager command line interface. The role parameter indicates the 
requested ACS user privilege level for this user (see below). 



 
124 January 28, 2014 
    public enum ACSSecurityRole : int 
    { 
        // ACS Roles 
        AcsCmAdmin = 2, 
        AcsCmOperator = 1, 
        AcsCmUser = 0 
    } 
Input parameters:  
 userName – username associated with the user 
 passwordString – password for this user. Password that do not adhere to standard 
windows user complexity requirements will result in API failure with appropriate error 
message thrown. 
 role - indicates the requested ACS user privilege level for this user. 
Sample response: 
<ChassisResponse 
xmlns="http://schemas.datacontract.org/2004/07/Microsoft.GFS.ACS.Contracts" 
xmlns:i="http://www.w3.org/2001/XMLSchema-instance"> 
  <completionCode>Success</completionCode>  
  <statusDescription></statusDescription> 
  <apiVersion>1</apiVersion> 
  </ChassisResponse> 
9.6.58 Changes Password for Existing Chassis Controller User 
ChassisResponse ChangeChassisControllerUserPassword(string userName, string 
newPassword) 
https://localhost:8000/ChangeChassisControllerUserPassword?userName=xxx 
&newPassword=yyyy 
Usage scenario: 
Changes the username and password for an existing user in the chassis controller. 
Input parameters:  
 userName 
 newpassword 
Sample response: 
<ChassisResponse 
xmlns="http://schemas.datacontract.org/2004/07/Microsoft.GFS.ACS.Contracts" 



Open Compute Project  Open CloudServer chassis management specification 
http://opencompute.org 125 
xmlns:i="http://www.w3.org/2001/XMLSchema-instance"> 
  <completionCode>Success</completionCode>  
  <statusDescription></statusDescription> 
  <apiVersion>1</apiVersion> 
  </ChassisResponse> 
9.6.59 Changes Role for Existing Chassis Controller User 
ChassisResponse ChangeChassisControllerUserRole(string userName, ACSSecurityRole 
role) 
https://localhost:8000/ChangeChassisControllerUserRole?userName=xxx &role=1 
Usage scenario: 
This API is used to change the role associated with the user (see below). 
    public enum ACSSecurityRole : int 
    { 
        // ACS Roles 
        AcsCmAdmin = 2, 
        AcsCmOperator = 1, 
        AcsCmUser = 0 
    } 
Input parameters:  
 userName 
 role 
Sample response: 
<ChassisResponse 
xmlns="http://schemas.datacontract.org/2004/07/Microsoft.GFS.ACS.Contracts" 
xmlns:i="http://www.w3.org/2001/XMLSchema-instance"> 
  <completionCode>Success</completionCode>  
  <statusDescription></statusDescription> 
  <apiVersion>1</apiVersion> 
  </ChassisResponse> 
9.6.60 Removes Existing Chassis Controller User 



 
126 January 28, 2014 
ChassisResponse RemoveChassisControllerUser(string userName) 
https://localhost:8000/RemoveChassisControllerUser?userName=xxx  
Usage scenario: 
This command is used to remove an existing chassis controller user. 
Input parameters:  
 userName 
Sample response: 
<ChassisResponse 
xmlns="http://schemas.datacontract.org/2004/07/Microsoft.GFS.ACS.Contracts" 
xmlns:i="http://www.w3.org/2001/XMLSchema-instance"> 
  <completionCode>Success</completionCode>  
  <statusDescription></statusDescription> 
  <apiVersion>1</apiVersion> 
  </ChassisResponse> 
9.6.61 Get health of Chassis 
ChassisHealthResponse GetChassisHealth(bool bladeHealth, bool psuHealth, bool 
fanHealth) 
https://localhost:8000/GetChassisHealth 
Usage Scenario: 
This API can be used for status/health monitoring of chassis devices such as blade, psu and 
fan. 
The BladeState attribute specified as part of the BladeShellResponse refers to one of the 
following five blade states, Initialize, Blade Enable Off, Probation, Healthy and Fail. Please refer 
to the blade state management diagram in ACS Software Architecture manual for more 
details. 
The BladeType attribute specified as part of the BladeShellResponse refers to the type of 
blade, server (compute server), JBod (storage server) or unknown (device not reachable or not 
populated) . 
 
Input Parameters: 
 bladeHealth 
 psuHealth 
 fanHealth 



Open Compute Project  Open CloudServer chassis management specification 
http://opencompute.org 127 
Note: If none of the parameters are specified, the API will fetch result for all components. 
Sample response: 
- <ChassisHealthResponse 
xmlns="http://schemas.datacontract.org/2004/07/Microsoft.GFS.ACS.Contracts" 
xmlns:i="http://www.w3.org/2001/XMLSchema-instance"> 
  <completionCode>Success</completionCode>  
  <statusDescription></statusDescription> 
  <apiVersion>1</apiVersion> 
- <bladeShellCollection> 
- <BladeShellResponse> 
  <completionCode>Success</completionCode>  
  <statusDescription></statusDescription> 
  <apiVersion>1</apiVersion> 
  <bladeId>1</bladeId>  
  <bladeState>Healthy</bladeState>  
  <bladeType>Server</bladeType>  
  </BladeShellResponse> 
- <BladeShellResponse> 
  <completionCode>Success</completionCode>  
  <statusDescription></statusDescription> 
  <apiVersion>1</apiVersion> 
  <bladeId>2</bladeId>  
  <bladeState>Healthy</bladeState>  
  <bladeType>Server</bladeType>  
  </BladeShellResponse> 
… 
- <BladeShellResponse> 
  <completionCode>Success</completionCode>  
  <statusDescription></statusDescription> 
  <apiVersion>1</apiVersion> 
  <bladeId>24</bladeId>  
  <bladeState>Fail</bladeState>  
  <bladeType>Unknown</bladeType>  



 
128 January 28, 2014 
  </BladeShellResponse> 
  </bladeShellCollection> 
- <fanInfoCollection> 
- <FanInfo> 
  <completionCode>Success</completionCode>  
  <statusDescription></statusDescription> 
  <apiVersion>1</apiVersion> 
  <fanId>1</fanId>  
  <fanSpeed>4109</fanSpeed>  
  <isFanHealthy>true</ isFanHealthy >  
  </FanInfo> 
- … 
<FanInfo> 
  <completionCode>Success</completionCode>  
  <statusDescription></statusDescription> 
  <apiVersion>1</apiVersion> 
  <fanId>6</fanId>  
  <fanSpeed>4094</fanSpeed>  
  < isFanHealthy >true</ isFanHealthy >  
  </FanInfo> 
  </fanInfoCollection> 
- <psuInfoCollection> 
- <PsuInfo> 
  <completionCode>Success</completionCode>  
  <statusDescription></statusDescription> 
  <apiVersion>1</apiVersion> 
  <id>1</id>  
  <powerOut>0</powerOut>  
  <serialNumber>46-49-51-44-31-32-33-37-30-30-31-30-32-34</serialNumber>  
  <state>ON</state>  
  </PsuInfo> 



Open Compute Project  Open CloudServer chassis management specification 
http://opencompute.org 129 
… 
- <PsuInfo> 
  <completionCode>Success</completionCode>  
  <statusDescription></statusDescription> 
  <apiVersion>1</apiVersion> 
  <id>6</id>  
  <powerOut>0</powerOut>  
  <serialNumber>46-49-51-44-31-32-33-37-30-30-31-30-35-38</serialNumber>  
  <state>ON</state>  
  </PsuInfo> 
  </psuInfoCollection> 
  </ChassisHealthResponse> 
9.6.62 Get Health of Blade 
BladeHealthResponse GetBladeHealth(int bladeId, bool cpuInfo, bool memInfo, bool 
diskInfo, bool pcieInfo, bool sensorInfo, bool temp, bool fruInfo) 
https://localhost:8000/GetBladeHealth?bladeid=2&cpuInfo=true&memInfo=true&diskInf
o=true&pcieInfo=true&sensorInfo=true&temp=true&fruInfo=true 
Usage Scenario: 
This API can be used for status/health monitoring of blade components such as cpu, memory, 
disk, pci, sensor, temperature, and FRU. 
Input Parameters: 
 bladeId  
 cpuInfo 
 memInfo 
 diskInfo 
 pcieInfo 
 sensorInfo 
 temp 
 fruInfo 
Note: Except for bladeId, other parameters are optional. If none of the other parameters are 
specified, the API will fetch result for all components. 
Sample response: 



 
130 January 28, 2014 
- <BladeHealthResponse 
xmlns="http://schemas.datacontract.org/2004/07/Microsoft.GFS.ACS.Contracts" 
xmlns:i="http://www.w3.org/2001/XMLSchema-instance"> 
  <completionCode>Success</completionCode>  
  <statusDescription></statusDescription> 
  <apiVersion>1</apiVersion> 
  <assetTag />  
- <bladeDisk> 
- <diskInfo> 
  <completionCode>Success</completionCode>  
  <statusDescription></statusDescription> 
  <apiVersion>1</apiVersion> 
  <diskId>243</diskId>  
  <diskStatus>0</diskStatus>  
  </diskInfo> 
- <diskInfo> 
  <completionCode>Success</completionCode>  
  <statusDescription></statusDescription> 
  <apiVersion>1</apiVersion> 
  <diskId>245</diskId>  
  <diskStatus>0</diskStatus>  
  </diskInfo> 
- <diskInfo> 
  <completionCode>Success</completionCode>  
  <statusDescription></statusDescription> 
  <apiVersion>1</apiVersion> 
  <diskId>246</diskId>  
  <diskStatus>0</diskStatus>  
  </diskInfo> 
  </bladeDisk> 
- <bladeShell> 
  <completionCode>Success</completionCode>  



Open Compute Project  Open CloudServer chassis management specification 
http://opencompute.org 131 
  <statusDescription></statusDescription> 
  <apiVersion>1</apiVersion> 
  <bladeId>2</bladeId>  
  <bladeState>Healthy</bladeState>  
  <bladeType>Server</bladeType>  
  </bladeShell> 
  <hardwareVersion>V1.0</hardwareVersion>  
  <JbodDiskInfo i:nil="true" />  
  <JbodInfo i:nil="true" />  
- <memoryInfo> 
- <memoryInfo> 
  <actualSpeed>false</actualSpeed>  
  <completionCode>Success</completionCode>  
  <statusDescription></statusDescription> 
  <apiVersion>1</apiVersion> 
  <dimm>0</dimm>  
  <dimmType>DDR3</dimmType>  
  <memVoltage>V13</memVoltage>  
  <size>8192</size>  
  <speed>1333</speed>  
  <status>Reserved</status>  
  </memoryInfo> 
- … 
<memoryInfo> 
  <actualSpeed>false</actualSpeed>  
  <completionCode>Success</completionCode>  
  <statusDescription></statusDescription> 
  <apiVersion>1</apiVersion> 
  <dimm>9</dimm>  
  <dimmType>DDR3</dimmType>  
  <memVoltage>V13</memVoltage>  
  <size>8192</size>  



 
132 January 28, 2014 
  <speed>1333</speed>  
  <status>Reserved</status>  
  </MemoryInfo> 
  </MemoryInfo> 
- <PcieInfo> 
- <PCIeInfo> 
  <completionCode>Success</completionCode>  
  <statusDescription></statusDescription> 
  <apiVersion>1</apiVersion> 
  <pcieNumber>1</pcieNumber>  
  <deviceId>65535</deviceId>  
  <subSystemId>65535</subSystemId>  
  <systemId>65535</systemId>  
  <vendorId>65535</vendorId>  
  </PCIeInfo> 
- <PCIeInfo> 
  <completionCode>Success</completionCode>  
  <statusDescription></statusDescription> 
  <apiVersion>1</apiVersion> 
  <pcieNumber>2</pcieNumber>  
  <deviceId>5463</deviceId>  
  <subSystemId>35221</subSystemId>  
  <systemId>5421</systemId>  
  <vendorId>32902</vendorId>  
  </PCIeInfo> 
- <PCIeInfo> 
  <completionCode>Success</completionCode>  
  <statusDescription></statusDescription> 
  <apiVersion>1</apiVersion> 
  <pcieNumber>3</pcieNumber>  
  <deviceId>65535</deviceId>  



Open Compute Project  Open CloudServer chassis management specification 
http://opencompute.org 133 
  <subSystemId>65535</subSystemId>  
  <systemId>65535</systemId>  
  <vendorId>65535</vendorId>  
  </PCIeInfo> 
  </PCIeInfo> 
- <processorInfo> 
- <processorInfo> 
  <completionCode>Failure</completionCode>  
  <statusDescription>Device did not return result</statusDescription> 
  <apiVersion>1</apiVersion> 
  <frequency>0</frequency>  
  <procId>0</procId>  
  <procType i:nil="true" />  
  <state i:nil="true" />  
  </processorInfo> 
  <productType />  
  <sensors />  
  <serialNumber>QTFCTM2350003</serialNumber>  
  </BladeHealthResponse> 
9.6.63 Get Next Boot Device 
BootResponse GetNextBoot(int bladeId) 
https://localhost:8000/GetNextBoot?bladeid=2 
Usage Scenario: 
This API gets the boot device of the blade after the next reboot. 
This command does not reflect the BIOS boot order.  The SetNextboot command acts as an 
interrupt before the BIOS boot order is initialized. If the SetNextBoot order is flagged with 
persistence it interrupts boot every time, until manual user intervention to change the BIOS 
manually (then the SetNextBoot is overridden and must be executed again). If it is not 
flagged with persistence the command will do a 1 time volatile override (if you hard power 
cycle volatile memory is lost, hence it needs to be a BMC power cycle). 
Input Parameters: 
 bladeId  



 
134 January 28, 2014 
Sample response: 
<BootResponse 
xmlns="http://schemas.datacontract.org/2004/07/Microsoft.GFS.ACS.Contracts" 
xmlns:i="http://www.w3.org/2001/XMLSchema-instance"> 
  <completionCode>Success</completionCode>  
  <statusDescription></statusDescription> 
  <apiVersion>1</apiVersion> 
  <nextBootString>NoOverRide</nextBootString>  
  </BootResponse> 
9.6.64 Set Next Boot Device 
BootResponse SetNextBoot(int bladeId, BladeBootType bootType, bool uefi, bool 
persistent, int bootInstance) 
https://localhost:8000/SetNextBoot?bladeid=2&bootType=2&uefi=false&persistent=false  
Usage Scenario: 
This API sets the boot device of the blade upon its next reboot. The boot device can be set 
using the bootType parameter from the list of devices specified in the enum below.  
This command does not change the BIOS boot order.  This command acts as an interrupt 
before the BIOS boot order is initialized. If the SetNextBoot order is flagged with persistence 
it interrupts boot every time, until manual user intervention to change the BIOS manually 
(then the SetNextBoot is overridden and must be executed again). If it is not flagged with 
persistence the command will do a 1 time volatile override (if you hard power cycle volatile 
memory is lost, hence it needs to be a BMC power cycle). 
    /// <summary> 
    /// Boot type for blades.  
    /// The boot should follow soon (within one minute) after the boot type is set. 
    /// </summary> 
    public enum BladeBootType : int 
    { 
        Unknown = 0, 
        NoOverRide = 1, 
        Pxe = 2, 
        Hdd = 3, 
        HddSafeMode = 4, 



Open Compute Project  Open CloudServer chassis management specification 
http://opencompute.org 135 
        DiagPartition = 5, 
        Dvd = 6, 
        BiosSetup = 7, 
        FloppyOrRemovable = 8 
    } 
 
Input Parameters: 
 bladeId  
 bootType: type of the boot device 
 uefi: true sets UEFI BIOS, false sets legacy BIOS 
 persistent: true sets it for all subsequent reboots, false sets it just for the next reboot 
 bootInstance: the instance of the boot device (for example, the second NIC card) 
Sample response: 
<BootResponse 
xmlns="http://schemas.datacontract.org/2004/07/Microsoft.GFS.ACS.Contracts" 
xmlns:i="http://www.w3.org/2001/XMLSchema-instance"> 
  <completionCode>Success</completionCode>  
  <statusDescription></statusDescription> 
  <apiVersion>1</apiVersion> 
<nextBootString>ForcePxe</nextBootString>  
</BootResponse> 
10 Command Line Interface 
The CLI is intended for service technicians or testers who need quick access to the 
chassis manager services and capabilities without having to use a browser or write a 
REST client. 
10.1 Install the Chassis Manager Service 
Table 38 lists the commands to install, start, stop, and uninstall the chassis manager 
service and to launch the command-line interface. 
Table 38. Commands to Install Chassis Manager Service and Launch the CLI 



 
136 January 28, 2014 
Action Command 
Install 
service 
CM-Binary-Directory> 
C:\Windows\Microsoft.NET\Framework\v4.0.30319\InstallUtil.exe 
Microsoft.GFS.WCS.ChassisManager.exe 
Start 
service net start chassismanager 
Stop 
service net stop chassismanager 
Uninstall 
service 
CM-Binary-Directory> 
C:\Windows\Microsoft.NET\Framework\v4.0.30319\InstallUtil.exe 
/u Microsoft.GFS.WCS.ChassisManager.exe 
Launch CLI 
WcsCli-Binary-Directory> wcscli  –h <hostname>  -p <port>  -s<SSL 
encryption option> [[-u] <username> [-x] <password>] [-b 
<batch_file_name>] 
-h <hostname>  
Host name of computer on which the chassis manager service is running 
-p <port>  
Port on which chassis manager Service is listening (It is usually 8000) 
-s  
<SSL encryption option>  
 Select 0- To disable SSL encryption. 
 Select 1-To enabled SSL encryption. 
-u and -x   
Optional parameters, user credentials (username(-u) and password(-x)) to connect to 
CM service. If not specified default credentials are used. 
B<Batch file name>  
Optional argument, use to execute commands from a batch file. 
Note that host name, port, and SSL encryption options are mandatory and should be 
supplied to launch the CLI. 
10.2 State and Information Commands 
The sections that follow describe the ACS system CLI commands, which provide 
information about the system state.` 
10.2.1 GetChassisInfo 



Open Compute Project  Open CloudServer chassis management specification 
http://opencompute.org 137 
Description:  
This command gets information about the whole chassis, including: 
 Blades – for example, GUID and power status  
 Power supplies – for example, power draw  status and serial number 
 chassis manager – version information, IP information, and system uptime  
Syntax: 
wcscli –getchassisinfo [-s] [-p] [-c] [-h] 
-s – Show information about blades  
-p – Show information about power supplies  
-c – Show chassis manager information 
-h – Help, display the correct syntax 
Sample usage: 
wcscli#  wcscli –s –p –c 
Sample output: 
== Compute Nodes == 
#       | Name  | GUID     | State | BMC MAC       | Completion Code 
1       | BLADE1        | 71cd4e40-a900-11e1-9856-089e013a37e8  | On    
| DeviceID: 0MAC Address: 08:9E:01:22:FB:42     | Success 
2       | BLADE2        | 590fbcc0-a910-11e1-b117-089e013a37f8  | On    
| DeviceID: 0MAC Address: 08:9E:01:22:FB:32     | Success 
3       | BLADE3        | b56945e0-a93d-11e1-be83-089e013a3809  | On    
| DeviceID: 0MAC Address: 08:9E:01:22:FB:3E     | Success 
4       | BLADE4        | 9f7f0a40-a83d-11e1-a8ad-089e013a3798  | On    
| DeviceID: 0MAC Address:  
08:9E:01:29:60:32     | Success 
5       | BLADE5        | ae7ee0a0-d50c-11e1-b27d-089e015a2876  | On    
| DeviceID: 0MAC Address: 08:9E:01:5A:2C:16     | Success 
6       | BLADE6        | 506d99c0-d4fd-11e1-b020-089e015a2872  | On    
| DeviceID: 0MAC Address: 08:9E:01:5A:2C:1C     | Success 
7       | BLADE7        | 07c79a60-d505-11e1-a944-089e015a2874  | On    
| DeviceID: 0MAC Address: 08:9E:01:5A:2C:0A     | Success 
8       | BLADE8        | 7b7398a0-d4e8-11e1-aa7a-089e015a286c  | On    
| DeviceID: 0MAC Address: 08:9E:01:5A:2C:18     | Success 
9       | BLADE9        | 3d54f900-d4df-11e1-a52d-089e015a286a  | On    
| DeviceID: 0MAC Address: 08:9E:01:5A:2C:1E     | Success 
10      | BLADE10       | dcfaf040-d4f3-11e1-8ce3-089e015a2870  | On    
| DeviceID: 0MAC Address: 08:9E:01:5A:2C:40     | Success 
…..... 
== Power Supplies == 



 
138 January 28, 2014 
#       | Serial Num    | State | Pout (W)      | Completion Code 
1       | 46-49-51-44-31-32-33-37-30-30-31-31-32-33     | On    | 194   
| Success 
2       | 46-49-51-44-31-32-33-37-30-30-31-31-32-38     | On    | 228   
| Success 
3       | 46-49-51-44-31-32-33-37-30-30-31-30-36-30     | On    | 190   
| Success 
4       | 46-49-51-44-31-32-33-37-30-30-31-30-38-33     | On    | 214   
| Success 
5       | 46-49-51-44-31-32-33-37-30-30-31-30-33-30     | On    | 188   
| Success 
6       | 46-49-51-44-31-32-33-37-30-30-31-30-32-39     | On    | 203   
| Success 
 
== Chassis Controller == 
Firmware Version        : 02.02 
Hardware Version        : 1 
Serial Number           : 33333333 
Asset Tag               : 
IP Address              : 192.168.100.23 
IP Address Source       : 192.168.100.8 
System Uptime           : 00:21:32.5127429 
10.2.2 GetBladeInfo 
Description:  
This command gets information about the blades, including serial number and version 
information. 
Syntax: 
wcscli -getbladeinfo [ -i <blade_index> | -a ] [-h] 
-i – Blade index (1-24)  
-a – Get information for all blades  
-h – Help, display the correct syntax 
Sample usage: 
To get information on blade 1, execute the following command: 
WcsCli# wcscli -getbladeinfo -i 2 
Sample output: 



Open Compute Project  Open CloudServer chassis management specification 
http://opencompute.org 139 
== Compute Node Info == 
Firmware Version        : 03.02 
Hardware Version        : MASFJ 
Serial Number           : SDJKJ2350005 
Asset Tag               : 
 
== MAC Address == 
Device Id                       : 0 
MAC Address             : 08:9E:01:22:FB:32 
10.2.3 GetChassisHealth 
Description:  
This command gets health status for blades, power supplies, and fans. 
Syntax: 
wcscli -getchassishealth [-b] [-p] [-f] [-h] 
-b – Show blade health  
-p – Show PSU health 
-f – Show fan health 
-h – Help, display the correct syntax 
Sample usage: 
To get information about blade 1, execute the following command: 
wcscli# wcscli –getchassishealth–b –p -f 
Sample output: 
== Blade Health == 
Blade Id        : 1 
Blade State     : Healthy 
Blade Type      : Server 
 
Blade Id        : 2 
Blade State     : Healthy 
Blade Type      : Server 
 
Blade Id        : 3 
Blade State     : Healthy 
Blade Type      : Server 
 



 
140 January 28, 2014 
Blade Id        : 4 
Blade State     : Fail 
Blade Type      : Server 
 
Blade Id        : 5 
Blade State     : Fail 
Blade Type      : Unknown 
 
Blade Id        : 6 
Blade State     : Fail 
Blade Type      : Unknown 
…… 
………. 
== PSU Health == 
Psu Id  : 1 
Psu Serial Number       : 46-49-51-44-31-32-33-37-30-30-31-3 
Psu State               : ON 
PSU Power Out           : 0 
Psu Completion code: Success 
 
Psu Id  : 2 
Psu Serial Number       : 46-49-51-44-31-32-33-37-30-30-31-3 
Psu State               : ON 
PSU Power Out           : 0 
Psu Completion code: Success 
 
Psu Id  : 3 
Psu Serial Number       : 46-49-51-44-31-32-33-37-30-30-31-3 
Psu State               : ON 
PSU Power Out           : 0 
Psu Completion code: Success 
 
Psu Id  : 4 
Psu Serial Number       : 46-49-51-44-31-32-33-37-30-30-31-3 
Psu State               : ON 
PSU Power Out           : 0 
Psu Completion code: Success 
 
Psu Id  : 5 
Psu Serial Number       : 46-49-51-44-31-32-33-37-30-30-31-3 



Open Compute Project  Open CloudServer chassis management specification 
http://opencompute.org 141 
Psu State               : ON 
PSU Power Out           : 0 
Psu Completion code: Success 
 
Psu Id  : 6 
Psu Serial Number       : 46-49-51-44-31-32-33-37-30-30-31-3 
Psu State               : ON 
PSU Power Out           : 0 
Psu Completion code: Success 
 
 
== Fan Health == 
Fan Id  : 1 
Fan Speed: 3670 
Fan status: ON 
 
Fan Id  : 2 
Fan Speed: 3683 
Fan status: ON 
 
Fan Id  : 3 
Fan Speed: 3474 
Fan status: ON 
 
Fan Id  : 4 
Fan Speed: 3468 
Fan status: ON 
 
Fan Id  : 5 
Fan Speed: 3633 
Fan status: ON 
 
Fan Id  : 6 
Fan Speed: 3571 
Fan status: ON 
10.2.4 GetBladeHealth 
Description:  
This command gets health information about the blade, including CPU, memory, disk, PCIe, 



 
142 January 28, 2014 
sensor, and FRU information. The information can be requested separately using specific 
command options. 
Syntax: 
wcscli -getbladehealth [-i <blade_index>] [-a] [-m] [-d] [-p] [-s] [-t] 
[-f] [-h] 
-a – Show blade CPU information  
-m – Show blade memory information 
-d – Show blade disk information 
-p – Show blade PCIe information 
-s – Show blade sensor information 
-t – Show temperature sensor information 
-f – Show blade FRU information 
-h – Help, display the correct syntax 
Sample usage: 
To get information on blade 1, execute the following command: 
wcscli# wcscli –getbladehealth –i 1  
Sample output: 
== Blade 2 Health Information == 
Blade ID        : 2 
Blade State     : Healthy 
Blade Type      : Server 
 
== Memory Information == 
Dimm    : 0 
Dimm Type       : DDR3 
Memory Voltage          : V13 
Size            : 8192 
Speed           : 1333 
Memory Status           : Reserved 
Actual Speed            : False 
 
Dimm    : 1 
Dimm Type       : DDR3 
Memory Voltage          : V13 
Size            : 8192 
Speed           : 1333 
Memory Status           : Reserved 



Open Compute Project  Open CloudServer chassis management specification 
http://opencompute.org 143 
Actual Speed            : False 
 
Dimm    : 2 
Dimm Type       : DDR3 
Memory Voltage          : V13 
Size            : 8192 
Speed           : 1333 
Memory Status           : Reserved 
Actual Speed            : False 
== Disk information == 
Disk Id : 243 
Disk Speed      : 0 
 
Disk Id : 244 
Disk Speed      : 0 
 
Disk Id : 245 
Disk Speed      : 0 
 
Disk Id : 246 
Disk Speed      : 0 
 
== PCIE Information == 
PCIE Id : 65535 
PCIE Number     : 1 
PCIE Sub System Id: 65535 
PCIE System Id          : 65535 
PCIE Vendor Id          : 65535 
 
PCIE Id : 5463 
PCIE Number     : 2 
PCIE Sub System Id   : 35221 
PCIE System Id          : 5421 
PCIE Vendor Id          : 32902 
 
PCIE Id : 114 
PCIE Number     : 3 
PCIE Sub System Id   : 35206 
PCIE System Id          : 5421 
PCIE Vendor Id          : 4096 
== FRU Information == 



 
144 January 28, 2014 
Blade Serial Number     : SADTR2370293 
Blade Asset Tag : 
Blade Product Type      : 
Blade Hardware Version  : ASFAS 
Note that some of the fields populated are blank as complete FRU data is not available for 
the on which the sample command was executed. 
10.3 Blade Management Commands 
The sections that follow describe the ACS system CLI blade management commands. 
10.3.1 SetPowerOn 
Description:  
This command turns the AC outlet power ON for the blades. 
When AC power gets supplied to the blade and the default blade power state is set to ON, 
the blade chipset will start to receive power and boot process will be initiated. If the default 
blade power state is set to OFF when AC power is applied, the blade chipset will not receive 
power (and the boot process will not be initiated). You can explicitly send a SetBladeOn 
command to power the blade on. 
Syntax: 
wcscli –setpoweron [-i <blade_index> | -a] [-h] 
-i – Blade index (1-24)  
-a – Get information for all blades 
-h – Help, display the correct syntax 
Sample usage: 
To turn the power ON on blade 3, use the following command: 
wcscli#  wcscli –setpoweron –i 3 
Sample output: 
OK 
10.3.2 SetPowerOff 
Description:  



Open Compute Project  Open CloudServer chassis management specification 
http://opencompute.org 145 
This command turns the AC outlet power OFF for the blades. 
Syntax: 
wcscli –setpoweroff [-i <blade_index> | -a] [-h] 
-i – Blade index (1-24)  
-a – Get information for all blades 
-h – Help, display the correct syntax 
Sample usage: 
To turn the power OFF on blade 3, use the following command: 
wcscli#  wcscli –setpoweroff –i 3 
Sample output: 
OK 
10.3.3 GetPowerState 
Description:  
This command gets the AC outlet power ON/OFF state of blades (whether or not the blades 
are receiving AC power). 
 When ON, blade is receiving AC power (hard power state).  
 When OFF, blade is not receiving AC power. 
Syntax: 
wcscli –getpowerstate [-i <blade_index> | -a] [-h] 
-i – Blade index (1-24)  
-a – Get information for all blades 
-h – Help, display the correct syntax 
Sample usage: 
To get the power state for blade 1, use the following command: 
wcscli#  wcscli –getpowerstate –i 1 
Sample output: 
Blade 5: On 
10.3.4 SetBladeOn 
Description:  



 
146 January 28, 2014 
This command supplies the power to the blade chipset, initializing the boot process. This 
command is used to soft power the blade ON. 
Syntax: 
wcscli –setbladeon [ -i <blade_index> | -a] [-h] 
-i – Blade index (1-24)  
-a – All connected blades 
-h – Help, display the correct syntax 
Sample usage: 
To soft power ON blade 1, use the following command: 
wcscli#  wcscli –setbladeon –i 1 
Sample output: 
Blade 1: ON 
10.3.5 SetBladeOff 
Description:  
This command removes the power from the blade chipset. This command is used to soft 
power the blade OFF. 
Syntax: 
wcscli –setbladeoff [[-i <blade_index>] |[-a]] [-h] 
-i – Blade index (1-48)  
-a – All connected blades 
-h – Help, display the correct syntax 
Sample usage: 
To soft power OFF blade 1, use the following command: 
wcscli#  wcscli –setbladeoff –i 1 
Sample output: 
Blade 1: OFF 
10.3.6 GetBladeState 
Description:  



Open Compute Project  Open CloudServer chassis management specification 
http://opencompute.org 147 
This command gets the ON/OFF state of the blade (whether the blade chipset is receiving 
power).  
 When ON, blade is receiving AC power (hard power state) and the chipset is receiving 
power (soft power state).  
 When OFF, blade chipset is not receiving power. 
Syntax: 
wcscli –getbladestate [[-i <blade_index>] | [-a]] [-h] 
-i – Blade index (1-24)  
-a – All connected blades 
-h – Help, display the correct syntax 
Sample usage: 
To get the ON/OFF state of blade 1, use the following command: 
wcscli#  wcscli –getbladestate –i 1 
Sample output: 
Blade State 1: ON 
10.3.7 SetBladeDefaultPowerState 
Description:  
This command sets the default power state of the blade ON/OFF.  
The default blade power state denotes the behavior of the blade after receiving AC power, 
either when a blade is initially inserted in to its slot or power returns after a utility failure. If 
the blade default power state is set to OFF, the blade won’t be powered ON after receiving 
AC input power. An explicit SetBladeOn command needs to be sent to power ON the blade. 
If the blade default power state is set to ON, the blade will be powered ON after receiving 
AC input power. 
Note that the blade default power state does not affect the active power state of the blade, 
only their behaviors after a hard power recycle. 
Syntax: 
wcscli – setbladedefaultpowerstate [[-i <blade_index>] | [-a] ] -s 
<state>[-h] 
-i – Blade index (1-24)  
-a – All connected blades 
-s – State, can be 0 (stay OFF) or 1 (power ON) 



 
148 January 28, 2014 
-h – Help, display the correct syntax 
Sample usage: 
To set the default power state of of blade 1 to ON, use the following command: 
wcscli#  wcscli –setbladedefaultpowerstate –i 1 -s 1 
Sample output: 
Blade 1 Default Power State:  
ON 
10.3.8 GetBladeDefaultPowerState 
Description:  
This command gets the default power state of the blade ON/OFF.  
Syntax: 
wcscli – getbladedefaultpowerstate [[-i <blade_index>] | [-a]][-h] 
-i – Blade index, the number of blades (1-24)  
-a – Gets information for all blades 
-h – Help, display the correct syntax 
Sample usage: 
To set the default power state of of blade 1 to ON, use the following command: 
wcscli#  wcscli –getbladedefaultpowerstate –i 1 
Sample output: 
Blade 1 Default Power State: ON 
10.3.9 SetBladeActivePowerCycle 
Description:  
This command power cycles or soft resets the blade(s).  
Power cycle resets the blade (causing a software reboot sequence).  Blade AC power signal 
remains ON throughout this process. Any serial session active on that blade will continue to 
be active during this process. 
Syntax: 



Open Compute Project  Open CloudServer chassis management specification 
http://opencompute.org 149 
wcscli – setbladeactivepowercycle [[-i <blade_index>]| [-a]] | [-t 
<off_time>][-h] 
-i – Blade index, the number of blades (1-24)  
-a – Gets information for all blades 
-t – Indicates the off time: the time interval in seconds for how long the blade stays OFF 
before power on. If not specified, the default interval is 0 seconds. 
-h – Help, display the correct syntax 
Sample usage: 
To power cycle blade 3, use the following command: 
wcscli#  wcscli – setbladeactivepowercycle –i 3 
 
Sample output: 
OK 
10.3.10 SetBladeAttentionLEDOn 
Description:  
This command turns the blade attention LED On. The purpose of this attention LED is to 
indicate that this blade needs attention. The command can also be used to identify the blade.  
The blade attention LED is used to help service technicians find the blade during repair. Users 
can also flag a service requirement by turning ON this LED. Operators/users must ensure that 
the blade attention LED is turned OFF after service is complete. 
Syntax: 
wcscli – setbladeattentionledon [[-i <blade_index>]| [-a]][-h] 
-i – Blade index, the number of blades (1-24)  
-a – Gets information for all blades 
-h – Help, display the correct syntax 
Sample usage: 
To turn the blade attention LED for blade 1 ON, use the following command: 
wcscli#  wcscli – setbladeattentionledon –i 1 
Sample output: 
OK 
 



 
150 January 28, 2014 
10.3.11 SetBladeAttentionLEDOff 
Description:  
This command turns the blade attention LED Off. The purpose of this attention LED is to 
indicate that this blade needs attention.  
The blade attention LED is used to help service technicians find the blade during repair. Users 
can also flag a service requirement by turning ON this LED. Operators/users must ensure that 
the blade attention LED is turned OFF after service is complete. 
Syntax: 
wcscli – setbladeattentionledoff [[-i <blade_index>]|[-a]][-h] 
-i – Blade index, the number of blades (1-24)  
-a – Gets information for all blades 
-h – Help, display the correct syntax 
Sample usage: 
To turn the blade attention LED for blade 1 OFF, use the following command: 
wcscli#  wcscli – setbladeattentionledoff –i 1 
Sample output: 
OK 
10.3.12 ReadBladeLog 
Description:  
This command reads the log from a blade.  The blade log (system event log) contains 
information about events/warnings/alerts pertaining to that blade like thermal throttling of 
blades due to overheating, etc. 
Syntax: 
wcscli – readsclog [-i <blade_index>] [-n <entries_count>] [-h] 
-i – Blade index, the number of blades (1-24)  
-n – How many of the most recent entries to report. This is an optional parameter; if not 
specified the command will return all existing entries. 
-h – Help, display the correct syntax 



Open Compute Project  Open CloudServer chassis management specification 
http://opencompute.org 151 
Sample usage: 
To read the blade log for blade 1 and log type 1, use the following command: 
wcscli#  wcscli –readsclog –i 1 –l 1 
Sample output: 
#       | EventTime   |    EventDescription                            
    
| 2012-08-23T14:35:21| Sensor_SpecificDrive_Slot2433328Assertion111    
| 2012-08-23T16:11:08| DiscreteTemperature187257Desertion3    
| 2012-08-23T18:35:21| Sensor_SpecificDrive_Slot2463328Assertion111 
| 2012-08-23T19:35:21| Sensor_SpecificDrive_Slot2433328Assertion111    
| 2012-08-23T20:35:21| Sensor_SpecificDrive_Slot2433328Assertion111 
10.3.13 ClearBladeLog 
Description:  
This command clears the log from a blade. 
Syntax: 
wcscli – clrsclog [-i <blade_index>] [-h] 
-i – Blade index, the number of blades (1-24)  
-h – Help, display the correct syntax 
Sample usage: 
To clear the blade log for blade 1, use the following command: 
wcscli#  wcscli –clearbladelog –i 1  
Sample output: 
OK 
10.3.14 SetBladePowerLimit 
Description:  
This command sets the power limit for a blade. 
The power limit can be set for a variety of reasons including energy savings and under 
provisioning (consolidate more servers under a power hierarchy). 
Syntax: 



 
152 January 28, 2014 
wcscli – setbladepowerlimit [[-i <blade_index>] | [-a ]] -l 
<power_limit> [-h] 
-i – Blade index, the number of blades (1-24)  
-a – Perform action for all blades  
-l – Blade power limit, in W  
-h – Help, display the correct syntax 
Sample usage: 
To set the power limit for blade 1 to 750 W, use the following command: 
wcscli#  wcscli –setbladepowerlimit –i 1 –l 750   
Sample output: 
Blade 1 power limit: 750 Watts 
10.3.15 SetBladePowerLimitOn 
Description:  
This command activates the power limit for a blade, and enables power throttling. 
Syntax: 
wcscli – setbladepowerlimiton [[-i <blade_index>]|[-a]] [-h] 
-i – Blade index, the number of blades (1-24)  
-a – Perform action for all blades  
-h – Help, display the correct syntax 
Sample usage: 
To activates the power limit for blade 1, use the following command: 
wcscli#  wcscli –setbladepowerlimiton –i 1  
Sample output: 
Blade 1: ON 
10.3.16 SetBladePowerLimitOff 
Description:  
This command deactivates the power limit for a blade, and disables power throttling. 
Syntax: 



Open Compute Project  Open CloudServer chassis management specification 
http://opencompute.org 153 
wcscli – setbladepowerlimitoff [[-i <blade_index>]|[-a]] [-h] 
-i – Blade index, the number of blades (1-24)  
-a – Perform action for all blades  
-h – Help, display the correct syntax 
Sample usage: 
To deactivates the power limit for blade 1, use the following command: 
wcscli#  wcscli –setbladepowerlimitoff –i 1  
Sample output: 
Blade 1: OFF 
10.3.17 GetBladePowerLimit 
Description:  
This command gets the power limit for a blade. 
Syntax: 
wcscli – getbladepowerlimit [[-i <blade_index>]|[-a]] [-h] 
-i – Blade index, the number of blades (1-24)  
-a – Perform action for all blades  
-h – Help, display the correct syntax 
Sample usage: 
To get the power limit for blade 1, use the following command: 
wcscli#  wcscli –getbladepowerlimit –i 1    
Sample output: 
Blade 1 power limit 750 Watts 
10.3.18 GetBladePowerReading 
Description:  
This command gets the power reading for a blade. The command can be used for monitoring 
and or other power control mechanism (refer to the SetBladePowerLimit command). 
Syntax: 
wcscli – getbladepowerreading [[-i <blade_index>]|[-a]] [-h] 



 
154 January 28, 2014 
-i – Blade index, the number of blades (1-24)  
-a – Perform action for all blades  
-h – Help, display the correct syntax 
Sample usage: 
To get the power reading for blade 1, use the following command: 
wcscli#  wcscli –getbladepowerreading –i 1    
Sample output: 
Blade 1 power reading: 67 Watts 
10.3.19 GetNextBoot 
Description:  
This command gets the device type of the start boot device during the subsequent reboot for 
a particular blade. 
Syntax: 
wcscli – getnextboot [-i <blade_index>][-h] 
-i – Blade index, the number of blades (1-24)  
-h – Help, display the correct syntax 
Sample usage: 
To get the next boot device type for blade 1, use the following command: 
wcscli#  wcscli –getnextbootdevice –i 1    
Sample output: 
OK. Next boot is ForcePxe. 
10.3.20 SetNextBoot 
Description:  
This command sets the device boot type of the start boot device during the subsequent 
reboot for a blade. 
Syntax: 
wcscli –setbootnext [-i <blade_index>] [-t <boot_type>] [-p 
<is_persistent>] [-n <boot_instance>] [-h] 



Open Compute Project  Open CloudServer chassis management specification 
http://opencompute.org 155 
-i – Blade index (1-24)  
boot_type – One of the following: 
1. NoOverRide 
2. ForcePxe 
3. ForceDefaultHdd,  
4. ForceDefaultHddSafeMode 
5. ForceDefaultDiagPartition,  
6. ForceDefaultDvd 
7. ForceIntoBiosSetup 
8. ForceFloppyOrRemovable 
is_persistent – Is this a persistent setting (set value 1) or a one-time setting (set value 0) 
boot_instance – instance number of the boot device (for example, 0 or 1 for NIC if there are 
two NICs) 
-h – Help, display the correct syntax 
Sample usage: 
To set the boot device for blade 1, use the following command: 
wcscli#  wcscli –setnextboot –i 2 –p 1 –n 1 
Sample output: 
OK. Next boot is ForceDefaultHdd 
10.4 Chassis Manager Management Commands 
The sections that follow describe the ACS system CLI chassis manager management 
commands 
10.4.1 SetChassisAttentionLEDOn 
Description:  
This command turns the Chassis attention LED On. The purpose of this attention LED is to 
indicate that this chassis manager needs attention.  
The chassis attention LED is used to direct service technicians to the correct chassis during 
repair. Users can also flag a service requirement by turning ON this LED. When possible, 
repairs will also be self-directed by the chassis management system. Operators/users must 
ensure that the Chassis Attention LED is turned OFF after service is complete. 
Syntax: 



 
156 January 28, 2014 
wcscli –setchassisattentionledon [-h] 
-h – Help, display the correct syntax 
Sample usage: 
To turn the chassis attention LED ON, use the following command: 
wcscli#  wcscli –setattentionledon 
Sample output: 
OK 
10.4.2 SetChassisAttentionLEDOff 
Description:  
This command turns the Chassis attention LED Off. The purpose of this attention LED is to 
indicate that this chassis manager needs attention.  
The chassis attention LED is used to direct service technicians to the correct chassis during 
repair. Users can also flag a service requirement by turning ON this LED. When possible, 
repairs will also be self-directed by the chassis management system. Operators/users must 
ensure that the Chassis Attention LED is turned OFF after service is complete. 
Syntax: 
wcscli –setchassisattentionledoff [-h] 
-h – Help, display the correct syntax 
Sample usage: 
To turn the chassis attention LED OFF, use the following command: 
wcscli#  wcscli –setattentionledoff 
Sample output: 
OK 
10.4.3 GetChassisAttentionLEDStatus 
Description:  
This command gets the status of the chassis attention LED (whether ON or OFF).  
The chassis attention LED is used to direct service technicians to the correct chassis during 
repair. Users can also flag a service requirement by turning ON this LED. When possible, 



Open Compute Project  Open CloudServer chassis management specification 
http://opencompute.org 157 
repairs will also be self-directed by the chassis management system. Operators/users must 
ensure that the Chassis Attention LED is turned OFF after service is complete. 
Syntax: 
wcscli –getchassisledstatus [-h] 
-h – Help, display the correct syntax 
Sample usage: 
To get the status of the chassis attention LED, use the following command: 
wcscli#  wcscli –getchassisledstatus 
Sample output: 
Chassis LED: OFF 
10.4.4 ReadChassisLog 
Description:  
This command reads the chassis log. 
The chassis log contains information about various alerts/warning messages associated with 
devices connected to the chassis manager (for example, blade overheating or fan/PSU failure). 
The chassis log also contains user audit information, such as timestamp/activity performed by 
that user. 
Syntax: 
wcscli –readchassislog [-h] 
-h – Help, display the correct syntax 
Sample usage: 
To get the chassis user log, use the following command: 
wcscli#  wcscli –readchassislog 
Sample output: 
== Chassis Controller Log == 
Timestamp       | Entry 
10/3/2012 3:22:56 PM    | <user>,Invoked 
GetChassisInfo(True,True,True) 
10/3/2012 3:22:57 PM    | <user>,Invoked GetBladeState(bladeid: 1) 



 
158 January 28, 2014 
10/3/2012 3:22:57 PM    | <user>,Invoked GetBladeState(bladeid: 2) 
10/3/2012 3:22:57 PM    | <user>,Invoked GetBladeState(bladeid: 3) 
10/3/2012 3:22:58 PM    | <user>,Invoked 
GetChassisNetworkProperties() 
10/3/2012 3:23:45 PM    | <user>,Invoked ReadBladelog(bladeId: 1) 
10.4.5 ClearChassisLog 
Description:  
This command clears the chassis log. 
To comply with size restrictions on chassis manager storage space, users are expected to 
periodically clear the consumed log entries. 
Syntax: 
wcscli –clearchassislog [-h] 
-h – Help, display the correct syntax 
Sample usage: 
To clear the chassis user log, use the following command: 
wcscli#  wcscli –clearchassislog 
Sample output: 
OK 
10.4.6 GetACSocketPowerState 
Description:  
This command gets the status of chassis AC sockets (TOR switches). 
The AC socket power state refers to active power state of the COM ports (and therefore to 
the power state of the device connected to the port) on the chassis manager. For example, 
the TOR switch is connected to COM1 (port number 1). The power ON/OFF commands for 
the AC sockets makes it possible to remotely power-reset the device and also for 
enabling/disabling purpose. 
Syntax: 
wcscli – getacsocketpowerstate -p <port_no> [-h] 



Open Compute Project  Open CloudServer chassis management specification 
http://opencompute.org 159 
-p – Port number of interest 
-h – Help, display the correct syntax 
Sample usage: 
To get the status of the chassis AC sockets for port 2, use the following command: 
wcscli#  wcscli –getacsocketpowerstate –p 2 
Sample output: 
ON 
10.4.7 SetACSocketPowerStateOn 
Description:  
This command turns the chassis AC sockets (TOR switches) ON. 
The AC socket power state refers to active power state of the COM ports (and therefore to 
the power state of the device connected to the port) on the chassis manager. For example, 
the TOR switch is connected to COM1 (port number 1). The power ON/OFF commands for 
the AC sockets makes it possible to remotely power-reset the device and also for 
enabling/disabling purpose. 
Syntax: 
wcscli – setacsocketpowerstateon -p <port_no> [-h] 
-p – Port number of interest 
-h – Help, display the correct syntax 
Sample usage: 
To turn ON the chassis AC sockets for port 12, use the following command: 
wcscli#  wcscli –setacsocketpowerstateon –p 12 
Sample output: 
OK 
10.4.8 SetACSocketPowerStateOff 
Description:  
This command turns the chassis AC sockets (TOR switches) OFF. 
The AC socket power state refers to active power state of the COM ports (and therefore to 



 
160 January 28, 2014 
the power state of the device connected to the port) on the chassis manager. For example, 
the TOR switch is connected to COM1 (port number 1). The power ON/OFF commands for 
the AC sockets makes it possible to remotely power-reset the device and also for 
enabling/disabling purpose. 
Syntax: 
wcscli – setacsocketpowerstateoff -p <port_no> [-h] 
-p – Port number of interest 
-h – Help, display the correct syntax 
Sample usage: 
To turn OFF the chassis AC sockets for port 12, use the following command: 
wcscli#  wcscli –setacsocketpowerstateoff –p 12 
Sample output: 
OK 
10.4.9 AddChassisControllerUser 
Description:  
This command adds a new chassis controller user with specified password and ACS security 
role for accessing the chassis manager command-line interface. The role should be Admin, 
Operator, or User. Each role has access to a specific set of APIs. 
Syntax: 
wcscli – adduser –u <username> -p <password> -a|-o|-r [-h] 
-u username – Username for the new user 
-p password – Password for the new user 
Select one of the ACS security roles for the user (mandatory): 
-a – Admin privilege 
-o – Operator privilege 
-r–  User privilege 
-h – Help, display the correct syntax 
Sample usage: 



Open Compute Project  Open CloudServer chassis management specification 
http://opencompute.org 161 
To add a user with admin privileges, use the following command: 
wcscli#  wcscli – adduser –u myname –p pass!123 -a 
Sample output: 
OK 
10.4.10 ChangeChassisControllerUserPassword 
Description:  
This command changes the password for an existing user in the chassis controller. 
Syntax: 
wcscli – changeuserpwd –u <username> -p <newpassword> [-h] 
-u username – Username for which the password will be changed 
-p newpassword – new password for the user 
-h – Help, display the correct syntax 
Sample usage: 
To add a user with admin privileges, use the following command: 
wcscli#  wcscli – changeuserpwd –u myname  –p pa##!143 
Sample output: 
OK 
10.4.11 ChangeChassisControllerUserRole 
Description:  
This command changes the ACS security role for an existing user in the chassis controller.  
Note that the user will be removed from other ACS security roles and added to the new role 
specified. Users can belong to only one security role. 
Syntax: 
wcscli – changeuserrole –u <username> -a|-o|-r [-h] 
-u username – Username for the new user 
Select one of the ACS security roles for the user (mandatory): 
-a – Admin privilege 



 
162 January 28, 2014 
-o – Operator privilege 
-r – User privilege 
-h – Help, display the correct syntax 
Sample usage: 
To change the user role to operator, use the following command: 
wcscli#  wcscli -changeuserrole –u myname  –o 
Sample output: 
OK 
10.4.12 RemoveChassisControllerUser 
Description:  
This command removes an existing user from the chassis controller. 
Syntax: 
wcscli – removeuser –u <username>[-h] 
-u username – Username for the new user 
-h – Help, display the correct syntax 
Sample usage: 
To remove a user, use the following command: 
wcscli#  wcscli -removeuser –u myname  
Sample output: 
OK 
10.4.13 GetNetworkProperties(getnic) 
Description:  
This command gets the chassis controller network properties. 
Syntax: 
wcscli – getnic[-h] 
-h – Help, display the correct syntax 



Open Compute Project  Open CloudServer chassis management specification 
http://opencompute.org 163 
Sample usage: 
To get the network configuration details for the chassis, use the following command: 
wcscli#  wcscli -getnic  
Sample output: 
Interface# 1 
IP: 192.168.100.13 
Subnet: 255.255.255.0 
Default gateway: 
DNS Domain: acs.lab 
DNS Hostname: CM_B1B01_1 
DHCP Server: 192.168.100.8 
MAC Address: 04:7D:7B:FC:4E:60 
Source :DHCP 
10.5 Blade and Serial Console Session Commands 
The sections that follow describe the ACS system CLI blade and serial console session 
commands. 
10.5.1 SetBladeSerialSession 
Description: 
This command is used to start serial session to a blade. The command will open a Serial-
Client-terminal for the serial session. 
Users might want to open a serial session to a blade for debugging purposes, to view blade 
boot messages, or for executing BIOS commands. A VT100 console will be provided that will 
continuously poll the blade for any serial session data. Any user command entered using the 
VT100 console will be sent to the blade. 
Note that this session might close unexpectedly if there is a simultaneous IPMI command 
issued to any of the chassis blades or because to inactivity of more than two minutes.  
Syntax: 
wcscli -startbladeserialsession [-i <blade_index>] [-h] 
blade_index - the number of the blade. Typically 1-24 



 
164 January 28, 2014 
-h - help; display the correct syntax 
Sample usage: 
To start a serial session to the blade, use the following command: 
wcscli# wcscli – startbladeserialsession -i blade_index 
Sample Output: 
This opens a VT100 session for that blade. 
10.5.2 StartPortSerialSession 
Description: 
This command is used to open a serial port console terminal to serial devices that are 
connected to the chassis manager (for example, TOR network switches). Note that the serial 
console might close if session is inactive for more than two minutes.  
Syntax:  
wcscli -startportserialsession [-i <Port_index>] [-h] 
Port_index - the number of the blade. Typically 1-2 
-h - help; display the correct syntax 
Sample usage: 
To to start serial port consolel, use the following command: 
wcscli# wcscli – startportserialsession -i port_index 
Sample output: 
This opens VT100 session for the serial port console. 
10.5.3 StopPortSerialSession 
Description: 
Stop all existing sessions on given port. 
Syntax:  
wcscli -stopPortSerialSession [-i <Port_index> [-h] 
-i Port number 
-h - Help; display the correct syntax 



Open Compute Project  Open CloudServer chassis management specification 
http://opencompute.org 165 
Sample usage: 
To to start serial port consolel, use the following command: 
wcscli# wcscli – stopPortSerialSession -i port_number 
Sample output: 
All existing sessions ended. 
 
10.5.4 EstablishCmConnection 
Description: 
Create a connection to the chassis manager service. 
Syntax:  
wcscli establishCmConnection -m <host_name> -p <port> -s <SSL_option> 
[-u] <username> [-x] <password> [-b] <batchfileName> [-h] 
-m host_name - Specify Host name for Chassis manager (for serial 
connection, localhost is assumed) 
-p port - Specify a valid Port to connect to for chassis manager 
(default is 8000) 
-s Select SSL Encryption enable/disable  
Enter 0 to disable SSl Encryption 
Enter 1 to enable SSl Encryption. 
-u & -x specify user credentials -- username and password -- to connect 
to CM service (Optional.. will use default credentials) 
-b Optional batch file option (not supported in serial mode). 
-v Get CLI version information 
-h help 
 
Sample usage: 
 
To establish a connection to the chassis manager, use the following command: 
wcscli# wcscli –establishCmConnection -p 8000 -s 0 -u username -x 
password 
Sample output: 
Connection to CM succeeded.. 



 
166 January 28, 2014 
10.5.5 TerminateCmConnection 
 
Description: 
Terminate a connection to the chassis manager service. 
Syntax:  
wcscli terminateCmConnection [-h] 
-h help 
Sample usage: 
To terminate a connection to the chassis manager, use the following command: 
wcscli# wcscli –terminateCmConnection 
Sample output: 
Connection to CM terminated successfully. 
10.6 CLI Over Serial (WCSCLI+) 
Note that these commans are available in WCSCLI Serial mode only. Otherwise, all these commands will 
fail with the following console message: 
Command only supported in serial wcscli client mode.. 
10.6.1 StartChassisManager 
Description: 
This command is used to start serial Windows chassis manager service. 
 Syntax: 
wcscli -startchassismanager [-h] 
-h - help; display the correct syntax 
Sample usage: 
To start the Windows chassis manager service, use the following command: 
wcscli# wcscli –startchassismanager 
Sample Output: 



Open Compute Project  Open CloudServer chassis management specification 
http://opencompute.org 167 
chassis manager successfully started. 
10.6.2 StopChassisManager 
Description: 
This command is used to stop an existing Windows chassis manager service.  
Syntax:  
wcscli -stopchassismanager [-h] 
-h - Help; display the correct syntax 
Sample usage: 
To stop Windows chassis manager service, use the following command: 
wcscli# wcscli –stopchassismanager 
Sample output: 
chassis manager service successfully stopped. 
10.6.3 GetChassisManagerStatus 
Description: 
Get the status of Windows chassis manager service. 
Syntax:  
wcscli -getchassismanagerstatus [-h] 
-h - Help; display the correct syntax 
Sample usage: 
To get the status of chassis manager service, use the following command: 
wcscli# wcscli –getchassismanagerstatus 
Sample output: 
chassismanager service status: Running 
OK 
10.6.4 EnableChassisManagerSsl 



 
168 January 28, 2014 
Description: 
Enable SSL for the chassis manager service. 
Syntax:  
wcscli -enablechassismanagerssl [-h] 
-h - Help; display the correct syntax 
Sample usage: 
To enable SSL for the chassis manager service, use the following command: 
wcscli# wcscli –enablechassismanagerssl 
Sample output: 
Successfully enabled SSL in the chassismanager service. 
You will need to establish connection to the CM again via establishCmConnection command 
to run any commands.. 
wcscli -establishCmConnection -m <host_name> -p <port> -s <SSL_option> [-u] 
<username> [-x] <password> [-b] <batchfileName> 
-m host_name - Specify Host name for Chassis manager (for serial connection, localhost is 
assumed) 
-p port - Specify a valid Port to connect to for chassis manager (default is 8000) 
-s Select SSL Encryption enable/disable  
Enter 0 to disable SSl Encryption 
Enter 1 to enable SSl Encryption. 
-u & -x specify user credentials -- username and password -- to connect to CM service 
(Optional.. will use default credentials) 
-b Optional batch file option (not supported in serial mode). 
-v Get CLI version information 
-h help 
10.6.5 DisableChassisManagerSsl 
Description: 
Disable SSL for the chassis manager service. 
Syntax:  



Open Compute Project  Open CloudServer chassis management specification 
http://opencompute.org 169 
wcscli -disablechassismanagerssl [-h] 
-h - Help; display the correct syntax 
Sample usage: 
To disable SSL for the chassis manager service, use the following command: 
wcscli# wcscli –disablechassismanagerssl 
Sample output: 
Successfully disabled SSL in the chassismanager service. 
You will need to establish connection to the CM again via establishCmConnection command 
to run any commands.. 
wcscli -establishCmConnection -m <host_name> -p <port> -s <SSL_option> [-u] 
<username> [-x] <password> [-b] <batchfileName> 
-m host_name - Specify Host name for Chassis manager (for serial connection, localhost is 
assumed) 
-p port - Specify a valid Port to connect to for chassis manager (default is 8000) 
-s Select SSL Encryption enable/disable  
Enter 0 to disable SSl Encryption 
Enter 1 to enable SSl Encryption. 
-u & -x specify user credentials -- username and password -- to connect to CM service 
(Optional.. will use default credentials) 
-b Optional batch file option (not supported in serial mode). 
-v Get CLI version information 
-h help 
10.6.6 GetNetworkProperties (getnic) 
Description:  
This command gets the chassis controller network properties. 
Syntax: 
wcscli – getnic[-h] 
-h – Help, display the correct syntax 
Sample usage: 



 
170 January 28, 2014 
To get the network configuration details for the chassis, use the following command: 
wcscli#  wcscli -getnic  
Sample output: 
N/w Interface# 1 
IP Address: 192.168.100.13 
Hostname: wcsprod 
MAC Address: 04:7D:7B:FC:4E:60 
Subnet Mask: 255.255.255.0 
DHCP Enabled:  
DHCP Server: 
DNS Domain: wcs.lab 
Gateway Address: 
Primary: 192.168.100.8 
Secondary: 
DNS Server:  
10.6.7 SetNetworkProperties (setnic) 
Description:  
This command sets the chassis controller network properties (only available over serial wcscli 
client). 
Syntax: 
wcscli -setnic [-n] <hostname> [-g] <gateway> [-s] <subnet> [-m] 
<netmask -Required!> [-i] <IP -Required!> [-p] <primary DNS -Required!> 
[-d] <secondary DNS -Required!> [-a] <IP addr source DHCP/STATIC -
Required!> [-h]  
-n - hostname of the chassis controller 
-g - gateway of the chassis controller 
-s - subnet IP of the chassis controller 
-m - subnet mask of the chassis controller 
-i - ip address of the chassis controller 
-p - primary DNS server address for the chassis controller 



Open Compute Project  Open CloudServer chassis management specification 
http://opencompute.org 171 
-d - secondary DNS server address for the chassis controller 
-a - IP addr source DHCP/STATIC 
-t - network interface number 
-h – help; display the correct syntax "; 
Sample usage: 
To get the network configuration details for the chassis, use the following command: 
wcscli#  wcscli -setnic -m 255.255.0.0 -i 10.160.148.220 -p 
10.160.148.220 -d 127.0.0.1 -a static 
Sample output: 
The command will execute successfully, and there will be intermittent connection loss to 
chassis manager because of the network cofig. update. 